# Altium SchDoc records: 05-GPS_IMU_SENSORS.SchDoc
|HEADER=Protel for Windows - Schematic Capture Binary File Version 5.0|Weight=2634|MinorVersion=6
|RECORD=31|FontIdCount=9|Size1=10|FontName1=Times New Roman|Size2=10|Rotation2=90|FontName2=Times New Roman|Size3=8|FontName3=Arial|Size4=10|FontName4=Arial|Size5=12|Underline5=T|FontName5=Arial|Size6=11|FontName6=Arial|Size7=24|FontName7=Times New Roman|Size8=10|Underline8=T|FontName8=Times New Roman|Size9=12|FontName9=Arial|UseMBCS=T|IsBOC=T|HotSpotGridOn=T|HotSpotGridSize=4|SheetStyle=12|SystemFont=4|BorderOn=T|SheetNumberSpaceSize=12|AreaColor=16317695|SnapGridOn=T|SnapGridSize=10|VisibleGridOn=T|VisibleGridSize=10|CustomX=2338|CustomX_Frac=58268|CustomY=1653|CustomY_Frac=54331|CustomXZones=8|CustomYZones=6|CustomMarginWidth=19|CustomMarginWidth_Frac=80000|ShowTemplateGraphics=T|TemplateFileName=C:\Users\<user>\Documents\Altium\AD20\Templates\Timecard.SchDot|Display_Unit=0
|RECORD=39|IsNotAccesible=T|OwnerPartId=-1|FileName=C:\Users\<user>\Documents\Altium\AD20\Templates\Timecard.SchDot
|RECORD=4|OwnerIndex=1|OwnerPartId=-1|Location.X=1594|Location.Y=39|Color=8388608|FontID=5|Text=timingcard.com|URL=http://timingcard.com
|RECORD=6|OwnerIndex=1|IndexInSheet=1|OwnerPartId=-1|LocationCount=2|X1=1680|Y1=35|X2=1576|Y2=35
|RECORD=4|OwnerIndex=1|IndexInSheet=2|OwnerPartId=-1|Location.X=1615|Location.Y=27|Justification=4|Color=16711680|FontID=6|Text==SheetNumber
|RECORD=4|OwnerIndex=1|IndexInSheet=3|OwnerPartId=-1|Location.X=1581|Location.X_Frac=42446|Location.Y=29|Location.Y_Frac=96838|Justification=3|FontID=3|Text=SHEET
|RECORD=4|OwnerIndex=1|IndexInSheet=4|OwnerPartId=-1|Location.X=1639|Location.X_Frac=42446|Location.Y=29|Location.Y_Frac=96838|Justification=3|FontID=3|Text=OF
|RECORD=6|OwnerIndex=1|IndexInSheet=5|OwnerPartId=-1|LineWidth=1|LocationCount=2|X1=1679|X1_Frac=42446|Y1=117|Y1_Frac=96838|X2=1576|Y2=118
|RECORD=4|OwnerIndex=1|IndexInSheet=6|OwnerPartId=-1|Location.X=1659|Location.Y=27|Justification=4|Color=16711680|FontID=6|Text==SheetTotal
|RECORD=30|OwnerIndex=1|IndexInSheet=7|OwnerPartId=-1|Location.X=1578|Location.Y=65|Corner.X=1673|Corner.X_Frac=88801|Corner.Y=115|KeepAspect=T|FileName=C:\Users\<user>\Desktop\Timecard Logo\TIMECARD.jpg
|RECORD=6|OwnerIndex=1|IndexInSheet=8|OwnerPartId=-1|LineWidth=1|LocationCount=2|X1=1576|X1_Frac=3162|Y1=117|Y1_Frac=42446|X2=1576|Y2=21
|RECORD=6|OwnerIndex=1|IndexInSheet=9|OwnerPartId=-1|LocationCount=2|X1=1680|Y1=51|X2=1576|Y2=51
|RECORD=4|OwnerIndex=1|IndexInSheet=10|OwnerPartId=-1|Location.X=1581|Location.X_Frac=42446|Location.Y=56|Location.Y_Frac=96838|Justification=3|FontID=3|Text=REV
|RECORD=4|OwnerIndex=1|IndexInSheet=11|OwnerPartId=-1|Location.X=1619|Location.Y=57|Justification=3|FontID=3|Text=DATE
|RECORD=6|OwnerIndex=1|IndexInSheet=12|OwnerPartId=-1|LocationCount=2|X1=1680|Y1=65|X2=1576|Y2=65
|RECORD=4|OwnerIndex=1|IndexInSheet=13|OwnerPartId=-1|Location.X=1605|Location.Y=58|Justification=4|Color=16711680|FontID=6|Text==ProjectRevision
|RECORD=4|OwnerIndex=1|IndexInSheet=14|OwnerPartId=-1|Location.X=1659|Location.Y=58|Justification=4|Color=16711680|FontID=6|Text==ProjectDate
|RECORD=41|IndexInSheet=1|OwnerPartId=-1|Location.X=21474|Location.X_Frac=83647|Location.Y=21464|Location.Y_Frac=83647|Color=8388608|FontID=1|IsHidden=T|Text=01910|Name=Customer
|RECORD=41|IndexInSheet=2|OwnerPartId=-1|Location.X=1000|Location.Y=10|Color=8388608|FontID=1|IsHidden=T|Text=*|Name=DocStatus
|RECORD=17|IndexInSheet=3|OwnerPartId=-1|ShowNetName=T|Location.X=290|Location.Y=880|Orientation=1|Color=128|FontID=1|Text=+5.0V
|RECORD=17|IndexInSheet=4|OwnerPartId=-1|Style=4|ShowNetName=T|Location.X=710|Location.Y=790|Orientation=3|Color=128|FontID=1|Text=GND
|RECORD=17|IndexInSheet=5|OwnerPartId=-1|ShowNetName=T|Location.X=190|Location.Y=880|Orientation=1|Color=128|FontID=1|Text=+3.3V
|RECORD=17|IndexInSheet=6|OwnerPartId=-1|Style=4|ShowNetName=T|Location.X=190|Location.Y=800|Orientation=3|Color=128|FontID=1|Text=GND
|RECORD=17|IndexInSheet=7|OwnerPartId=-1|Style=4|ShowNetName=T|Location.X=290|Location.Y=800|Orientation=3|Color=128|FontID=1|Text=GND
|RECORD=17|IndexInSheet=8|OwnerPartId=-1|ShowNetName=T|Location.X=780|Location.Y=850|Color=255|FontID=1|Text=GPS1_TP2|IsCrossSheetConnector=T
|RECORD=17|IndexInSheet=9|OwnerPartId=-1|ShowNetName=T|Location.X=780|Location.Y=840|Color=255|FontID=1|Text=GPS1_TP1|IsCrossSheetConnector=T
|RECORD=17|IndexInSheet=10|OwnerPartId=-1|ShowNetName=T|Location.X=780|Location.Y=830|Color=255|FontID=1|Text=GPS1_RX|IsCrossSheetConnector=T
|RECORD=17|IndexInSheet=11|OwnerPartId=-1|ShowNetName=T|Location.X=440|Location.Y=840|Orientation=2|Color=255|FontID=1|Text=GPS1_TX|IsCrossSheetConnector=T
|RECORD=17|IndexInSheet=12|OwnerPartId=-1|ShowNetName=T|Location.X=440|Location.Y=830|Orientation=2|Color=255|FontID=1|Text=GPS1_RST|IsCrossSheetConnector=T
|RECORD=4|IndexInSheet=13|OwnerPartId=-1|Location.X=580|Location.Y=1050|Color=8388608|FontID=7|Text=GPS
|RECORD=1|LibReference=RCB-F9T|ComponentDescription=MOD, GPS|PartCount=2|DisplayModeCount=1|IndexInSheet=14|OwnerPartId=-1|Location.X=610|Location.Y=850|CurrentPartId=1|LibraryPath=*|SourceLibraryName=Modules.IntLib|TargetFileName=*|AreaColor=11599871|Color=128|PartIDLocked=F|PinsMoveable=T|DesignItemId=RCB-F9T|AllPinCount=8
|RECORD=41|OwnerIndex=30|OwnerPartId=-1|Location.X=610|Location.Y=850|Color=8388608|FontID=9|IsHidden=T|Text=RCB-F9T|Name=MFG PART NUM
|RECORD=41|OwnerIndex=30|IndexInSheet=1|OwnerPartId=-1|Location.X=610|Location.Y=850|Color=8388608|FontID=9|IsHidden=T|Text=UBLOCKS|Name=MFG NAME
|RECORD=41|OwnerIndex=30|IndexInSheet=2|OwnerPartId=-1|Location.X=610|Location.Y=850|Color=8388608|FontID=9|IsHidden=T|Text=MOD|Name=CATEGORY
|RECORD=41|OwnerIndex=30|IndexInSheet=3|OwnerPartId=-1|Location.X=610|Location.Y=850|Color=8388608|FontID=9|IsHidden=T|Text=9/11/13|Name=MODIFY DATE
|RECORD=41|OwnerIndex=30|IndexInSheet=4|OwnerPartId=-1|Location.X=608|Location.Y=599|Color=8388608|FontID=1|IsHidden=T|Text=GPS|Name=P1
|RECORD=41|OwnerIndex=30|IndexInSheet=5|OwnerPartId=-1|Location.X=608|Location.Y=599|Color=8388608|FontID=1|IsHidden=T|Name=P2
|RECORD=41|OwnerIndex=30|IndexInSheet=6|OwnerPartId=-1|Location.X=608|Location.Y=599|Color=8388608|FontID=1|IsHidden=T|Name=P3
|RECORD=41|OwnerIndex=30|IndexInSheet=7|OwnerPartId=-1|Location.X=608|Location.Y=599|Color=8388608|FontID=1|IsHidden=T|Name=OTHER
|RECORD=41|OwnerIndex=30|IndexInSheet=8|OwnerPartId=-1|Location.X=608|Location.Y=599|Color=8388608|FontID=1|IsHidden=T|Name=DATE
|RECORD=41|OwnerIndex=30|IndexInSheet=9|OwnerPartId=-1|Location.X=608|Location.Y=599|Color=8388608|FontID=1|IsHidden=T|Text=*|Name=SHEETPART
|RECORD=41|OwnerIndex=30|IndexInSheet=10|OwnerPartId=-1|Location.X=608|Location.Y=599|Color=8388608|FontID=1|IsHidden=T|Name=SUB
|RECORD=41|OwnerIndex=30|IndexInSheet=11|OwnerPartId=-1|Location.X=608|Location.Y=599|Color=8388608|FontID=1|IsHidden=T|Name=SIZE
|RECORD=41|OwnerIndex=30|IndexInSheet=12|OwnerPartId=-1|Location.X=608|Location.Y=599|Color=8388608|FontID=1|IsHidden=T|Text=-40C|Name=MINTEMP
|RECORD=41|OwnerIndex=30|IndexInSheet=13|OwnerPartId=-1|Location.X=608|Location.Y=599|Color=8388608|FontID=1|IsHidden=T|Text=80C|Name=MAXTEMP
|RECORD=41|OwnerIndex=30|IndexInSheet=14|OwnerPartId=-1|Location.X=608|Location.Y=589|Color=8388608|FontID=1|IsHidden=T|Text=.|Name=DATE
|RECORD=41|OwnerIndex=30|IndexInSheet=15|OwnerPartId=-1|Location.X=608|Location.Y=904|Color=8388608|FontID=1|IsHidden=T|Text=MOD BLE 4.2|Name=DESC
|RECORD=41|OwnerIndex=30|IndexInSheet=16|OwnerPartId=-1|Location.X=578|Location.Y=922|Color=8388608|FontID=1|IsHidden=T|Text=<V PART NUM>|Name=VELENTIUM PART NUM
|RECORD=41|OwnerIndex=30|IndexInSheet=17|OwnerPartId=-1|Location.X=528|Location.Y=904|Color=8388608|FontID=1|IsHidden=T|Text=Digi-Key|Name=Supplier 1|ReadOnlyState=3
|RECORD=41|OwnerIndex=30|IndexInSheet=18|OwnerPartId=-1|Location.X=528|Location.Y=904|Color=8388608|FontID=1|IsHidden=T|Text=672-RCB-F9T-ND|Name=Supplier Part Number 1|ReadOnlyState=3
|RECORD=14|OwnerIndex=30|IsNotAccesible=T|IndexInSheet=19|OwnerPartId=1|Location.X=560|Location.Y=820|Corner.X=660|Corner.Y=870|Color=128|AreaColor=11599871|IsSolid=T
|RECORD=2|OwnerIndex=30|OwnerPartId=1|FormalType=1|Electrical=4|PinConglomerate=26|PinLength=30|Location.X=560|Location.Y=860|Name=VCC_ANT|Designator=1|SwapIDPart=Ž&Ž||PinPropagationDelay=0.000000E+000
|RECORD=2|OwnerIndex=30|OwnerPartId=1|FormalType=1|Electrical=4|PinConglomerate=26|PinLength=30|Location.X=560|Location.Y=850|Name=VCC|Designator=2|SwapIDPart=Ž&Ž||PinPropagationDelay=0.000000E+000
|RECORD=2|OwnerIndex=30|OwnerPartId=1|FormalType=1|Electrical=4|PinConglomerate=26|PinLength=30|Location.X=560|Location.Y=840|Name=TXD|Designator=3|SwapIDPart=Ž&Ž||PinPropagationDelay=0.000000E+000
|RECORD=2|OwnerIndex=30|OwnerPartId=1|FormalType=1|Electrical=4|PinConglomerate=26|PinLength=30|Location.X=560|Location.Y=830|Name=RST|Designator=4|SwapIDPart=Ž&Ž||PinPropagationDelay=0.000000E+000
|RECORD=2|OwnerIndex=30|OwnerPartId=1|FormalType=1|Electrical=4|PinConglomerate=24|PinLength=30|Location.X=660|Location.Y=830|Name=RXD|Designator=5|SwapIDPart=Ž&Ž||PinPropagationDelay=0.000000E+000
|RECORD=2|OwnerIndex=30|OwnerPartId=1|FormalType=1|Electrical=4|PinConglomerate=24|PinLength=30|Location.X=660|Location.Y=840|Name=TP1|Designator=6|SwapIDPart=Ž&Ž||PinPropagationDelay=0.000000E+000
|RECORD=2|OwnerIndex=30|OwnerPartId=1|FormalType=1|Electrical=4|PinConglomerate=24|PinLength=30|Location.X=660|Location.Y=850|Name=TP2|Designator=7|SwapIDPart=Ž&Ž||PinPropagationDelay=0.000000E+000
|RECORD=2|OwnerIndex=30|OwnerPartId=1|FormalType=1|Electrical=4|PinConglomerate=24|PinLength=30|Location.X=660|Location.Y=860|Name=GND|Designator=8|SwapIDPart=Ž&Ž||PinPropagationDelay=0.000000E+000
|RECORD=34|OwnerIndex=30|IndexInSheet=-1|OwnerPartId=-1|Location.X=560|Location.Y=870|Color=8388608|FontID=1|Text=U9|Name=Designator|ReadOnlyState=1
|RECORD=41|OwnerIndex=30|IndexInSheet=-1|OwnerPartId=-1|Location.X=560|Location.Y=808|Color=8388608|FontID=1|Text=RCB-F9T|Name=Comment
|RECORD=44|OwnerIndex=30
|RECORD=45|OwnerIndex=69|IndexInSheet=-1|ModelName=GNSS|ModelType=PCBLIB|DatafileCount=1|ModelDatafileEntity0=GNSS|ModelDatafileKind0=PCBLib|IsCurrent=T|IntegratedModel=T|DatabaseModel=T
|RECORD=46|OwnerIndex=70
|RECORD=48|OwnerIndex=70
|RECORD=1|LibReference=93fe34f5f049140596bab6421a6454b|ComponentDescription=IC EEPROM 2K I2C 1MHZ SOT23-5|PartCount=2|DisplayModeCount=1|IndexInSheet=15|OwnerPartId=-1|Location.X=1450|Location.Y=810|CurrentPartId=1|LibraryPath=*|SourceLibraryName=Altium Content Vault|TargetFileName=*|AreaColor=11599871|Color=128|PartIDLocked=T|DesignItemId=CMP-06313-000011-1|AllPinCount=5
|RECORD=14|OwnerIndex=73|IsNotAccesible=T|OwnerPartId=1|Location.X=1470|Location.Y=760|Corner.X=1540|Corner.Y=820|LineWidth=1|Color=128|AreaColor=11599871|IsSolid=T
|RECORD=2|OwnerIndex=73|OwnerPartId=1|Electrical=7|PinConglomerate=58|PinLength=20|Location.X=1470|Location.Y=810|Name=VCC|Designator=4|PinPropagationDelay=0.000000E+000
|RECORD=2|OwnerIndex=73|OwnerPartId=1|SymBol_InnerEdge=3|PinConglomerate=56|PinLength=20|Location.X=1540|Location.Y=810|Name=SCL|Designator=1|PinPropagationDelay=0.000000E+000
|RECORD=2|OwnerIndex=73|OwnerPartId=1|Electrical=1|PinConglomerate=56|PinLength=20|Location.X=1540|Location.Y=800|Name=SDA|Designator=3|PinPropagationDelay=0.000000E+000
|RECORD=2|OwnerIndex=73|OwnerPartId=1|PinConglomerate=58|PinLength=20|Location.X=1470|Location.Y=770|Name=WP|Designator=5|PinPropagationDelay=0.000000E+000
|RECORD=2|OwnerIndex=73|OwnerPartId=1|Electrical=7|PinConglomerate=56|PinLength=20|Location.X=1540|Location.Y=770|Name=GND|Designator=2|PinPropagationDelay=0.000000E+000
|RECORD=41|OwnerIndex=73|IndexInSheet=6|OwnerPartId=-1|Location.X=1448|Location.Y=820|Color=8388608|FontID=1|IsHidden=T|Text=-40°C|Name=Temperature Range Low
|RECORD=41|OwnerIndex=73|IndexInSheet=7|OwnerPartId=-1|Location.X=1448|Location.Y=820|Color=8388608|FontID=1|IsHidden=T|Text=1mm|Name=Height
|RECORD=41|OwnerIndex=73|IndexInSheet=8|OwnerPartId=-1|Location.X=1448|Location.Y=820|Color=8388608|FontID=8|IsHidden=T|Text=http://ww1.microchip.com/downloads/en/DeviceDoc/Atmel-8807-SEEPROM-AT24MAC402-602-Datasheet.pdf|Name=ComponentLink2URL
|RECORD=41|OwnerIndex=73|IndexInSheet=9|OwnerPartId=-1|Location.X=1448|Location.Y=820|Color=8388608|FontID=1|IsHidden=T|Text=SOT95P280X100-5|Name=Ipc Land Pattern Name
|RECORD=41|OwnerIndex=73|IndexInSheet=10|OwnerPartId=-1|Location.X=1448|Location.Y=820|Color=8388608|FontID=1|IsHidden=T|Text=2Kbits|Name=Memory Size
|RECORD=41|OwnerIndex=73|IndexInSheet=11|OwnerPartId=-1|Location.X=1448|Location.Y=820|Color=8388608|FontID=1|IsHidden=T|Text=IC|Name=Category
|RECORD=41|OwnerIndex=73|IndexInSheet=12|OwnerPartId=-1|Location.X=1448|Location.Y=820|Color=8388608|FontID=1|IsHidden=T|Text=EEPROM|Name=Memory Type
|RECORD=41|OwnerIndex=73|IndexInSheet=13|OwnerPartId=-1|Location.X=1448|Location.Y=820|Color=8388608|FontID=1|IsHidden=T|Text=IC EEPROM 2K I2C 1MHZ SOT23-5|Name=Digikey Description
|RECORD=41|OwnerIndex=73|IndexInSheet=14|OwnerPartId=-1|Location.X=1448|Location.Y=820|Color=8388608|FontID=1|IsHidden=T|Text=1.7V|Name=Min Supply Voltage
|RECORD=41|OwnerIndex=73|IndexInSheet=15|OwnerPartId=-1|Location.X=1448|Location.Y=820|Color=8388608|FontID=1|IsHidden=T|Text=AT24MAC402-STUM-T|Name=Manufacturer Part Number
|RECORD=41|OwnerIndex=73|IndexInSheet=16|OwnerPartId=-1|Location.X=1448|Location.Y=820|Color=8388608|FontID=1|IsHidden=T|Text=Integrated Circuits (ICs)|Name=Device Class L1
|RECORD=41|OwnerIndex=73|IndexInSheet=17|OwnerPartId=-1|Location.X=1448|Location.Y=820|Color=8388608|FontID=1|IsHidden=T|Text=+85°C|Name=Temperature Range High
|RECORD=41|OwnerIndex=73|IndexInSheet=18|OwnerPartId=-1|Location.X=1448|Location.Y=820|Color=8388608|FontID=1|IsHidden=T|Text=Datasheet|Name=ComponentLink2Description
|RECORD=41|OwnerIndex=73|IndexInSheet=19|OwnerPartId=-1|Location.X=1448|Location.Y=820|Color=8388608|FontID=1|IsHidden=T|Text=5.5V|Name=Max Supply Voltage
|RECORD=41|OwnerIndex=73|IndexInSheet=20|OwnerPartId=-1|Location.X=1448|Location.Y=820|Color=8388608|FontID=1|IsHidden=T|Text=TRUE|Name=RoHS
|RECORD=41|OwnerIndex=73|IndexInSheet=21|OwnerPartId=-1|Location.X=1448|Location.Y=820|Color=8388608|FontID=1|IsHidden=T|Text=1000kHz|Name=Frequency
|RECORD=41|OwnerIndex=73|IndexInSheet=22|OwnerPartId=-1|Location.X=1448|Location.Y=820|Color=8388608|FontID=1|IsHidden=T|Text=EEPROM Serial-I2C 2K-bit 256 x 8 1.8V/2.5V/3.3V/5V 5-Pin SOT-23 T/R|Name=Mouser Description
|RECORD=41|OwnerIndex=73|IndexInSheet=23|OwnerPartId=-1|Location.X=1448|Location.Y=820|Color=8388608|FontID=1|IsHidden=T|Text=Microchip|Name=Manufacturer
|RECORD=41|OwnerIndex=73|IndexInSheet=24|OwnerPartId=-1|Location.X=1448|Location.Y=820|Color=8388608|FontID=1|IsHidden=T|Text=0mm|Name=Standoff Height
|RECORD=41|OwnerIndex=73|IndexInSheet=25|OwnerPartId=-1|Location.X=1448|Location.Y=820|Color=8388608|FontID=8|IsHidden=T|Text=https://octopart.com/at24mac402-stum-t-microchip-77758112|Name=Octopart
|RECORD=41|OwnerIndex=73|IndexInSheet=26|OwnerPartId=-1|Location.X=1448|Location.Y=820|Color=8388608|FontID=1|IsHidden=T|Text=0.4-2mA|Name=Nominal Supply Current
|RECORD=41|OwnerIndex=73|IndexInSheet=27|OwnerPartId=-1|Location.X=1448|Location.Y=820|Color=8388608|FontID=1|IsHidden=T|Text=-40°C to +85°C|Name=Temperature
|RECORD=41|OwnerIndex=73|IndexInSheet=28|OwnerPartId=-1|Location.X=1448|Location.Y=820|Color=8388608|FontID=1|IsHidden=T|Text=5TS1|Name=Package
|RECORD=41|OwnerIndex=73|IndexInSheet=29|OwnerPartId=-1|Location.X=1448|Location.Y=820|Color=8388608|FontID=1|IsHidden=T|Text=EEPROM|Name=Device Class L3
|RECORD=41|OwnerIndex=73|IndexInSheet=30|OwnerPartId=-1|Location.X=1448|Location.Y=820|Color=8388608|FontID=1|IsHidden=T|Text=No|Name=Automotive
|RECORD=41|OwnerIndex=73|IndexInSheet=31|OwnerPartId=-1|Location.X=1448|Location.Y=820|Color=8388608|FontID=1|IsHidden=T|Text=0.55us|Name=Access Time
|RECORD=41|OwnerIndex=73|IndexInSheet=32|OwnerPartId=-1|Location.X=1448|Location.Y=820|Color=8388608|FontID=1|IsHidden=T|Text=Memory|Name=Device Class L2
|RECORD=41|OwnerIndex=73|IndexInSheet=33|OwnerPartId=-1|Location.X=1448|Location.Y=820|Color=8388608|FontID=1|IsHidden=T|Text=Yes|Name=Lead Free
|RECORD=41|OwnerIndex=73|IndexInSheet=34|OwnerPartId=-1|Location.X=1448|Location.Y=820|Color=8388608|FontID=1|IsHidden=T|Text=I2C,2-Wire|Name=Interface
|RECORD=34|OwnerIndex=73|IndexInSheet=-1|OwnerPartId=-1|Location.X=1470|Location.Y=820|Color=8388608|FontID=1|Text=U7|Name=Designator|ReadOnlyState=1
|RECORD=41|OwnerIndex=73|IndexInSheet=-1|OwnerPartId=1|Location.X=1470|Location.Y=750|Color=8388608|FontID=1|Text=AT24MAC402-STUM-T|Name=Comment
|RECORD=44|OwnerIndex=73
|RECORD=45|OwnerIndex=116|IndexInSheet=-1|UseComponentLibrary=T|ModelName=FP-5TS1-IPC_C|ModelType=PCBLIB|DatafileCount=1|ModelDatafileEntity0=FP-5TS1-IPC_C|ModelDatafileKind0=PCBLib|IsCurrent=T|DatalinksLocked=T|DatabaseDatalinksLocked=T
|RECORD=46|OwnerIndex=117
|RECORD=48|OwnerIndex=117
|RECORD=45|OwnerIndex=116|IndexInSheet=-1|UseComponentLibrary=T|ModelName=FP-5TS1-IPC_B|ModelType=PCBLIB|DatafileCount=1|ModelDatafileEntity0=FP-5TS1-IPC_B|ModelDatafileKind0=PCBLib|DatalinksLocked=T|DatabaseDatalinksLocked=T
|RECORD=46|OwnerIndex=120
|RECORD=48|OwnerIndex=120
|RECORD=45|OwnerIndex=116|IndexInSheet=-1|UseComponentLibrary=T|ModelName=FP-5TS1-IPC_A|ModelType=PCBLIB|DatafileCount=1|ModelDatafileEntity0=FP-5TS1-IPC_A|ModelDatafileKind0=PCBLib|DatalinksLocked=T|DatabaseDatalinksLocked=T
|RECORD=46|OwnerIndex=123
|RECORD=48|OwnerIndex=123
|RECORD=17|IndexInSheet=16|OwnerPartId=-1|ShowNetName=T|Location.X=1640|Location.Y=800|Color=255|FontID=1|Text=SDA|IsCrossSheetConnector=T
|RECORD=17|IndexInSheet=17|OwnerPartId=-1|ShowNetName=T|Location.X=1640|Location.Y=810|Color=255|FontID=1|Text=SCL|IsCrossSheetConnector=T
|RECORD=17|IndexInSheet=18|OwnerPartId=-1|ShowNetName=T|Location.X=1410|Location.Y=860|Orientation=1|Color=128|FontID=1|Text=+3.3V
|RECORD=17|IndexInSheet=19|OwnerPartId=-1|Style=4|ShowNetName=T|Location.X=1600|Location.Y=710|Orientation=3|Color=128|FontID=1|Text=GND
|RECORD=1|LibReference=CAP|ComponentDescription=C0603X104K5RACAUTO|PartCount=2|DisplayModeCount=2|IndexInSheet=20|OwnerPartId=-1|Location.X=230|Location.Y=820|Orientation=1|CurrentPartId=1|SourceLibraryName=Altium Content Vault|TargetFileName=*|AreaColor=11599871|Color=128|PartIDLocked=F|DesignItemId=CMP-2006-00003-1|AllPinCount=2
|RECORD=2|OwnerIndex=130|OwnerPartId=1|OwnerPartDisplayMode=1|FormalType=1|Electrical=4|PinConglomerate=35|PinLength=10|Location.X=240|Location.Y=820|Name=1|Designator=1|PinPropagationDelay=0.000000E+000
|RECORD=2|OwnerIndex=130|OwnerPartId=1|OwnerPartDisplayMode=1|FormalType=1|Electrical=4|PinConglomerate=33|PinLength=10|Location.X=240|Location.Y=830|Name=2|Designator=2|PinPropagationDelay=0.000000E+000
|RECORD=13|OwnerIndex=130|IsNotAccesible=T|IndexInSheet=2|OwnerPartId=1|OwnerPartDisplayMode=1|Location.X=248|Location.Y=820|Corner.X=232|Corner.Y=820|LineWidth=1|Color=16711680
|RECORD=13|OwnerIndex=130|IsNotAccesible=T|IndexInSheet=3|OwnerPartId=1|OwnerPartDisplayMode=1|Location.X=240|Location.Y=824|Corner.X=240|Corner.Y=830|LineWidth=1|Color=16711680
|RECORD=12|OwnerIndex=130|IsNotAccesible=T|IndexInSheet=4|OwnerPartId=1|OwnerPartDisplayMode=1|Location.X=240|Location.Y=840|Radius=16|LineWidth=1|StartAngle=241.000|EndAngle=270.000|Color=16711680
|RECORD=12|OwnerIndex=130|IsNotAccesible=T|IndexInSheet=5|OwnerPartId=1|OwnerPartDisplayMode=1|Location.X=240|Location.Y=840|Radius=16|LineWidth=1|StartAngle=270.000|EndAngle=299.000|Color=16711680
|RECORD=2|OwnerIndex=130|OwnerPartId=1|FormalType=1|Electrical=4|PinConglomerate=35|PinLength=10|Location.X=240|Location.Y=820|Name=1|Designator=1|PinPropagationDelay=0.000000E+000
|RECORD=2|OwnerIndex=130|OwnerPartId=1|FormalType=1|Electrical=4|PinConglomerate=33|PinLength=10|Location.X=240|Location.Y=830|Name=2|Designator=2|PinPropagationDelay=0.000000E+000
|RECORD=13|OwnerIndex=130|IsNotAccesible=T|IndexInSheet=8|OwnerPartId=1|Location.X=232|Location.Y=827|Corner.X=248|Corner.Y=827|LineWidth=1|Color=16711680
|RECORD=13|OwnerIndex=130|IsNotAccesible=T|IndexInSheet=9|OwnerPartId=1|Location.X=248|Location.Y=823|Corner.X=232|Corner.Y=823|LineWidth=1|Color=16711680
|RECORD=6|OwnerIndex=130|IsNotAccesible=T|IndexInSheet=10|OwnerPartId=1|LineWidth=1|Color=16711680|LocationCount=2|X1=240|Y1=820|X2=240|Y2=823
|RECORD=6|OwnerIndex=130|IsNotAccesible=T|IndexInSheet=11|OwnerPartId=1|LineWidth=1|Color=16711680|LocationCount=2|X1=240|Y1=830|X2=240|Y2=827
|RECORD=41|OwnerIndex=130|IndexInSheet=12|OwnerPartId=-1|Location.X=231|Location.Y=842|Color=8388608|FontID=1|IsHidden=T|Text=Kemet|Name=Manufacturer
|RECORD=41|OwnerIndex=130|IndexInSheet=13|OwnerPartId=-1|Location.X=231|Location.Y=842|Color=8388608|FontID=1|IsHidden=T|Text=C0603X104K5RACAUTO|Name=Part Number
|RECORD=34|OwnerIndex=130|IndexInSheet=-1|OwnerPartId=-1|Location.X=249|Location.Y=821|Color=8388608|FontID=1|Text=C59|Name=Designator|ReadOnlyState=1
|RECORD=41|OwnerIndex=130|IndexInSheet=-1|OwnerPartId=-1|Location.X=249|Location.Y=811|Color=8388608|FontID=1|Text=0.1uF|Name=Comment
|RECORD=44|OwnerIndex=130
|RECORD=45|OwnerIndex=151|IndexInSheet=-1|Description=Chip Capacitor, 2-Leads, Body 1.60x0.80mm, IPC Low Density|UseComponentLibrary=T|ModelName=CAPC1608X87X45ML20T05|ModelType=PCBLIB|DatafileCount=1|ModelDatafileEntity0=CAPC1608X87X45ML20T05|ModelDatafileKind0=PCBLib|IsCurrent=T|DatalinksLocked=T|DatabaseDatalinksLocked=T
|RECORD=46|OwnerIndex=152
|RECORD=48|OwnerIndex=152
|RECORD=41|OwnerIndex=154|IndexInSheet=-1|OwnerPartId=-1|Color=8388608|FontID=1|Text=2D|Name=Available Preview Images
|RECORD=45|OwnerIndex=151|IndexInSheet=-1|Description=Chip Capacitor, 2-Leads, Body 1.60x0.80mm, IPC High Density|UseComponentLibrary=T|ModelName=CAPC1608X87X45LL20T05|ModelType=PCBLIB|DatafileCount=1|ModelDatafileEntity0=CAPC1608X87X45LL20T05|ModelDatafileKind0=PCBLib|DatalinksLocked=T|DatabaseDatalinksLocked=T
|RECORD=46|OwnerIndex=156
|RECORD=48|OwnerIndex=156
|RECORD=41|OwnerIndex=158|IndexInSheet=-1|OwnerPartId=-1|Color=8388608|FontID=1|Text=2D|Name=Available Preview Images
|RECORD=45|OwnerIndex=151|IndexInSheet=-1|Description=Chip Capacitor, 2-Leads, Body 1.60x0.80mm, IPC Medium Density|UseComponentLibrary=T|ModelName=CAPC1608X87X45NL20T05|ModelType=PCBLIB|DatafileCount=1|ModelDatafileEntity0=CAPC1608X87X45NL20T05|ModelDatafileKind0=PCBLib|DatalinksLocked=T|DatabaseDatalinksLocked=T
|RECORD=46|OwnerIndex=160
|RECORD=48|OwnerIndex=160
|RECORD=41|OwnerIndex=162|IndexInSheet=-1|OwnerPartId=-1|Color=8388608|FontID=1|Text=2D|Name=Available Preview Images
|RECORD=1|LibReference=CAP|ComponentDescription=C0603X104K5RACAUTO|PartCount=2|DisplayModeCount=2|IndexInSheet=21|OwnerPartId=-1|Location.X=330|Location.Y=820|Orientation=1|CurrentPartId=1|SourceLibraryName=Altium Content Vault|TargetFileName=*|AreaColor=11599871|Color=128|PartIDLocked=F|DesignItemId=CMP-2006-00003-1|AllPinCount=2
|RECORD=2|OwnerIndex=164|OwnerPartId=1|OwnerPartDisplayMode=1|FormalType=1|Electrical=4|PinConglomerate=35|PinLength=10|Location.X=340|Location.Y=820|Name=1|Designator=1|PinPropagationDelay=0.000000E+000
|RECORD=2|OwnerIndex=164|OwnerPartId=1|OwnerPartDisplayMode=1|FormalType=1|Electrical=4|PinConglomerate=33|PinLength=10|Location.X=340|Location.Y=830|Name=2|Designator=2|PinPropagationDelay=0.000000E+000
|RECORD=13|OwnerIndex=164|IsNotAccesible=T|IndexInSheet=2|OwnerPartId=1|OwnerPartDisplayMode=1|Location.X=348|Location.Y=820|Corner.X=332|Corner.Y=820|LineWidth=1|Color=16711680
|RECORD=13|OwnerIndex=164|IsNotAccesible=T|IndexInSheet=3|OwnerPartId=1|OwnerPartDisplayMode=1|Location.X=340|Location.Y=824|Corner.X=340|Corner.Y=830|LineWidth=1|Color=16711680
|RECORD=12|OwnerIndex=164|IsNotAccesible=T|IndexInSheet=4|OwnerPartId=1|OwnerPartDisplayMode=1|Location.X=340|Location.Y=840|Radius=16|LineWidth=1|StartAngle=241.000|EndAngle=270.000|Color=16711680
|RECORD=12|OwnerIndex=164|IsNotAccesible=T|IndexInSheet=5|OwnerPartId=1|OwnerPartDisplayMode=1|Location.X=340|Location.Y=840|Radius=16|LineWidth=1|StartAngle=270.000|EndAngle=299.000|Color=16711680
|RECORD=2|OwnerIndex=164|OwnerPartId=1|FormalType=1|Electrical=4|PinConglomerate=35|PinLength=10|Location.X=340|Location.Y=820|Name=1|Designator=1|PinPropagationDelay=0.000000E+000
|RECORD=2|OwnerIndex=164|OwnerPartId=1|FormalType=1|Electrical=4|PinConglomerate=33|PinLength=10|Location.X=340|Location.Y=830|Name=2|Designator=2|PinPropagationDelay=0.000000E+000
|RECORD=13|OwnerIndex=164|IsNotAccesible=T|IndexInSheet=8|OwnerPartId=1|Location.X=332|Location.Y=827|Corner.X=348|Corner.Y=827|LineWidth=1|Color=16711680
|RECORD=13|OwnerIndex=164|IsNotAccesible=T|IndexInSheet=9|OwnerPartId=1|Location.X=348|Location.Y=823|Corner.X=332|Corner.Y=823|LineWidth=1|Color=16711680
|RECORD=6|OwnerIndex=164|IsNotAccesible=T|IndexInSheet=10|OwnerPartId=1|LineWidth=1|Color=16711680|LocationCount=2|X1=340|Y1=820|X2=340|Y2=823
|RECORD=6|OwnerIndex=164|IsNotAccesible=T|IndexInSheet=11|OwnerPartId=1|LineWidth=1|Color=16711680|LocationCount=2|X1=340|Y1=830|X2=340|Y2=827
|RECORD=41|OwnerIndex=164|IndexInSheet=12|OwnerPartId=-1|Location.X=331|Location.Y=842|Color=8388608|FontID=1|IsHidden=T|Text=Kemet|Name=Manufacturer
|RECORD=41|OwnerIndex=164|IndexInSheet=13|OwnerPartId=-1|Location.X=331|Location.Y=842|Color=8388608|FontID=1|IsHidden=T|Text=C0603X104K5RACAUTO|Name=Part Number
|RECORD=34|OwnerIndex=164|IndexInSheet=-1|OwnerPartId=-1|Location.X=349|Location.Y=821|Color=8388608|FontID=1|Text=C61|Name=Designator|ReadOnlyState=1
|RECORD=41|OwnerIndex=164|IndexInSheet=-1|OwnerPartId=-1|Location.X=349|Location.Y=811|Color=8388608|FontID=1|Text=0.1uF|Name=Comment
|RECORD=44|OwnerIndex=164
|RECORD=45|OwnerIndex=185|IndexInSheet=-1|Description=Chip Capacitor, 2-Leads, Body 1.60x0.80mm, IPC Low Density|UseComponentLibrary=T|ModelName=CAPC1608X87X45ML20T05|ModelType=PCBLIB|DatafileCount=1|ModelDatafileEntity0=CAPC1608X87X45ML20T05|ModelDatafileKind0=PCBLib|IsCurrent=T|DatalinksLocked=T|DatabaseDatalinksLocked=T
|RECORD=46|OwnerIndex=186
|RECORD=48|OwnerIndex=186
|RECORD=41|OwnerIndex=188|IndexInSheet=-1|OwnerPartId=-1|Color=8388608|FontID=1|Text=2D|Name=Available Preview Images
|RECORD=45|OwnerIndex=185|IndexInSheet=-1|Description=Chip Capacitor, 2-Leads, Body 1.60x0.80mm, IPC High Density|UseComponentLibrary=T|ModelName=CAPC1608X87X45LL20T05|ModelType=PCBLIB|DatafileCount=1|ModelDatafileEntity0=CAPC1608X87X45LL20T05|ModelDatafileKind0=PCBLib|DatalinksLocked=T|DatabaseDatalinksLocked=T
|RECORD=46|OwnerIndex=190
|RECORD=48|OwnerIndex=190
|RECORD=41|OwnerIndex=192|IndexInSheet=-1|OwnerPartId=-1|Color=8388608|FontID=1|Text=2D|Name=Available Preview Images
|RECORD=45|OwnerIndex=185|IndexInSheet=-1|Description=Chip Capacitor, 2-Leads, Body 1.60x0.80mm, IPC Medium Density|UseComponentLibrary=T|ModelName=CAPC1608X87X45NL20T05|ModelType=PCBLIB|DatafileCount=1|ModelDatafileEntity0=CAPC1608X87X45NL20T05|ModelDatafileKind0=PCBLib|DatalinksLocked=T|DatabaseDatalinksLocked=T
|RECORD=46|OwnerIndex=194
|RECORD=48|OwnerIndex=194
|RECORD=41|OwnerIndex=196|IndexInSheet=-1|OwnerPartId=-1|Color=8388608|FontID=1|Text=2D|Name=Available Preview Images
|RECORD=1|LibReference=CAP|ComponentDescription=C0603X104K5RACAUTO|PartCount=2|DisplayModeCount=2|IndexInSheet=22|OwnerPartId=-1|Location.X=1400|Location.Y=730|Orientation=1|CurrentPartId=1|SourceLibraryName=Altium Content Vault|TargetFileName=*|AreaColor=11599871|Color=128|PartIDLocked=F|DesignItemId=CMP-2006-00003-1|AllPinCount=2
|RECORD=2|OwnerIndex=198|OwnerPartId=1|OwnerPartDisplayMode=1|FormalType=1|Electrical=4|PinConglomerate=35|PinLength=10|Location.X=1410|Location.Y=730|Name=1|Designator=1|PinPropagationDelay=0.000000E+000
|RECORD=2|OwnerIndex=198|OwnerPartId=1|OwnerPartDisplayMode=1|FormalType=1|Electrical=4|PinConglomerate=33|PinLength=10|Location.X=1410|Location.Y=740|Name=2|Designator=2|PinPropagationDelay=0.000000E+000
|RECORD=13|OwnerIndex=198|IsNotAccesible=T|IndexInSheet=2|OwnerPartId=1|OwnerPartDisplayMode=1|Location.X=1418|Location.Y=730|Corner.X=1402|Corner.Y=730|LineWidth=1|Color=16711680
|RECORD=13|OwnerIndex=198|IsNotAccesible=T|IndexInSheet=3|OwnerPartId=1|OwnerPartDisplayMode=1|Location.X=1410|Location.Y=734|Corner.X=1410|Corner.Y=740|LineWidth=1|Color=16711680
|RECORD=12|OwnerIndex=198|IsNotAccesible=T|IndexInSheet=4|OwnerPartId=1|OwnerPartDisplayMode=1|Location.X=1410|Location.Y=750|Radius=16|LineWidth=1|StartAngle=241.000|EndAngle=270.000|Color=16711680
|RECORD=12|OwnerIndex=198|IsNotAccesible=T|IndexInSheet=5|OwnerPartId=1|OwnerPartDisplayMode=1|Location.X=1410|Location.Y=750|Radius=16|LineWidth=1|StartAngle=270.000|EndAngle=299.000|Color=16711680
|RECORD=2|OwnerIndex=198|OwnerPartId=1|FormalType=1|Electrical=4|PinConglomerate=35|PinLength=10|Location.X=1410|Location.Y=730|Name=1|Designator=1|PinPropagationDelay=0.000000E+000
|RECORD=2|OwnerIndex=198|OwnerPartId=1|FormalType=1|Electrical=4|PinConglomerate=33|PinLength=10|Location.X=1410|Location.Y=740|Name=2|Designator=2|PinPropagationDelay=0.000000E+000
|RECORD=13|OwnerIndex=198|IsNotAccesible=T|IndexInSheet=8|OwnerPartId=1|Location.X=1402|Location.Y=737|Corner.X=1418|Corner.Y=737|LineWidth=1|Color=16711680
|RECORD=13|OwnerIndex=198|IsNotAccesible=T|IndexInSheet=9|OwnerPartId=1|Location.X=1418|Location.Y=733|Corner.X=1402|Corner.Y=733|LineWidth=1|Color=16711680
|RECORD=6|OwnerIndex=198|IsNotAccesible=T|IndexInSheet=10|OwnerPartId=1|LineWidth=1|Color=16711680|LocationCount=2|X1=1410|Y1=730|X2=1410|Y2=733
|RECORD=6|OwnerIndex=198|IsNotAccesible=T|IndexInSheet=11|OwnerPartId=1|LineWidth=1|Color=16711680|LocationCount=2|X1=1410|Y1=740|X2=1410|Y2=737
|RECORD=41|OwnerIndex=198|IndexInSheet=12|OwnerPartId=-1|Location.X=1401|Location.Y=752|Color=8388608|FontID=1|IsHidden=T|Text=Kemet|Name=Manufacturer
|RECORD=41|OwnerIndex=198|IndexInSheet=13|OwnerPartId=-1|Location.X=1401|Location.Y=752|Color=8388608|FontID=1|IsHidden=T|Text=C0603X104K5RACAUTO|Name=Part Number
|RECORD=34|OwnerIndex=198|IndexInSheet=-1|OwnerPartId=-1|Location.X=1419|Location.Y=731|Color=8388608|FontID=1|Text=C25|Name=Designator|ReadOnlyState=1
|RECORD=41|OwnerIndex=198|IndexInSheet=-1|OwnerPartId=-1|Location.X=1419|Location.Y=721|Color=8388608|FontID=1|Text=0.1uF|Name=Comment
|RECORD=44|OwnerIndex=198
|RECORD=45|OwnerIndex=219|IndexInSheet=-1|Description=Chip Capacitor, 2-Leads, Body 1.60x0.80mm, IPC Low Density|UseComponentLibrary=T|ModelName=CAPC1608X87X45ML20T05|ModelType=PCBLIB|DatafileCount=1|ModelDatafileEntity0=CAPC1608X87X45ML20T05|ModelDatafileKind0=PCBLib|IsCurrent=T|DatalinksLocked=T|DatabaseDatalinksLocked=T
|RECORD=46|OwnerIndex=220
|RECORD=48|OwnerIndex=220
|RECORD=41|OwnerIndex=222|IndexInSheet=-1|OwnerPartId=-1|Color=8388608|FontID=1|Text=2D|Name=Available Preview Images
|RECORD=45|OwnerIndex=219|IndexInSheet=-1|Description=Chip Capacitor, 2-Leads, Body 1.60x0.80mm, IPC High Density|UseComponentLibrary=T|ModelName=CAPC1608X87X45LL20T05|ModelType=PCBLIB|DatafileCount=1|ModelDatafileEntity0=CAPC1608X87X45LL20T05|ModelDatafileKind0=PCBLib|DatalinksLocked=T|DatabaseDatalinksLocked=T
|RECORD=46|OwnerIndex=224
|RECORD=48|OwnerIndex=224
|RECORD=41|OwnerIndex=226|IndexInSheet=-1|OwnerPartId=-1|Color=8388608|FontID=1|Text=2D|Name=Available Preview Images
|RECORD=45|OwnerIndex=219|IndexInSheet=-1|Description=Chip Capacitor, 2-Leads, Body 1.60x0.80mm, IPC Medium Density|UseComponentLibrary=T|ModelName=CAPC1608X87X45NL20T05|ModelType=PCBLIB|DatafileCount=1|ModelDatafileEntity0=CAPC1608X87X45NL20T05|ModelDatafileKind0=PCBLib|DatalinksLocked=T|DatabaseDatalinksLocked=T
|RECORD=46|OwnerIndex=228
|RECORD=48|OwnerIndex=228
|RECORD=41|OwnerIndex=230|IndexInSheet=-1|OwnerPartId=-1|Color=8388608|FontID=1|Text=2D|Name=Available Preview Images
|RECORD=17|IndexInSheet=23|OwnerPartId=-1|ShowNetName=T|Location.X=1360|Location.Y=860|Orientation=1|Color=128|FontID=1|Text=+3.3V
|RECORD=17|IndexInSheet=24|OwnerPartId=-1|Style=4|ShowNetName=T|Location.X=1410|Location.Y=710|Orientation=3|Color=128|FontID=1|Text=GND
|RECORD=17|IndexInSheet=25|OwnerPartId=-1|ShowNetName=T|Location.X=1340|Location.Y=770|Orientation=2|Color=255|FontID=1|Text=EXT_EEPROM_WP|IsCrossSheetConnector=T
|RECORD=1|LibReference=RES-2|ComponentDescription=Chip Resistor, 10 KOhm, +/- 1%, 0.1 W, -55 to 155 degC, 0603 (1608 Metric), RoHS, Tape and Reel RMCF0603FT10K0|PartCount=2|DisplayModeCount=1|IndexInSheet=26|OwnerPartId=-1|Location.X=1360|Location.Y=810|Orientation=1|CurrentPartId=1|LibraryPath=*|SourceLibraryName=Altium Content Vault|TargetFileName=*|AreaColor=11599871|Color=128|PartIDLocked=T|DesignItemId=CMP-2000-06990-1|AllPinCount=2
|RECORD=2|OwnerIndex=235|OwnerPartId=1|FormalType=1|Electrical=4|PinConglomerate=33|PinLength=10|Location.X=1360|Location.Y=830|Name=2|Designator=2|PinPropagationDelay=0.000000E+000
|RECORD=2|OwnerIndex=235|OwnerPartId=1|FormalType=1|Electrical=4|PinConglomerate=35|PinLength=10|Location.X=1360|Location.Y=810|Name=1|Designator=1|PinPropagationDelay=0.000000E+000
|RECORD=6|OwnerIndex=235|IsNotAccesible=T|IndexInSheet=2|OwnerPartId=1|LineWidth=1|Color=16711680|LocationCount=10|X1=1360|Y1=830|X2=1360|Y2=826|X3=1362|Y3=825|X4=1358|Y4=823|X5=1362|Y5=821|X6=1358|Y6=819|X7=1362|Y7=817|X8=1358|Y8=815|X9=1360|Y9=814|X10=1360|Y10=810
|RECORD=41|OwnerIndex=235|IndexInSheet=3|OwnerPartId=-1|Location.X=1357|Location.Y=842|Color=8388608|FontID=1|IsHidden=T|Text=0603(1608Metric)|Name=Package / Case
|RECORD=41|OwnerIndex=235|IndexInSheet=4|OwnerPartId=-1|Location.X=1357|Location.Y=842|Color=8388608|FontID=1|IsHidden=T|Text=01/2017|Name=Datasheet Version
|RECORD=41|OwnerIndex=235|IndexInSheet=5|OwnerPartId=-1|Location.X=1357|Location.Y=842|Color=8388608|FontID=1|IsHidden=T|Text=10k|Name=Resistance (Ohms)
|RECORD=41|OwnerIndex=235|IndexInSheet=6|OwnerPartId=-1|Location.X=1357|Location.Y=842|Color=8388608|FontID=1|IsHidden=T|Text=AutomotiveAEC-Q200|Name=Features
|RECORD=41|OwnerIndex=235|IndexInSheet=7|OwnerPartId=-1|Location.X=1357|Location.Y=842|Color=8388608|FontID=1|IsHidden=T|Text=CutTape(CT)|Name=Packaging
|RECORD=41|OwnerIndex=235|IndexInSheet=8|OwnerPartId=-1|Location.X=1357|Location.Y=842|Color=8388608|FontID=1|IsHidden=T|Text=RMCF|Name=Series
|RECORD=41|OwnerIndex=235|IndexInSheet=9|OwnerPartId=-1|Location.X=1357|Location.Y=842|Color=8388608|FontID=1|IsHidden=T|Text=0.022"(0.55mm)|Name=Height
|RECORD=41|OwnerIndex=235|IndexInSheet=10|OwnerPartId=-1|Location.X=1357|Location.Y=842|Color=8388608|FontID=1|IsHidden=T|Text=±1%|Name=Tolerance
|RECORD=41|OwnerIndex=235|IndexInSheet=11|OwnerPartId=-1|Location.X=1357|Location.Y=842|Color=8388608|FontID=8|IsHidden=T|Text=https://www.seielect.com/|Name=Manufacturer URL
|RECORD=41|OwnerIndex=235|IndexInSheet=12|OwnerPartId=-1|Location.X=1357|Location.Y=842|Color=8388608|FontID=8|IsHidden=T|Text=https://www.seielect.com/Catalog/SEI-RMCF_RMCP.pdf|Name=Datasheet URL
|RECORD=41|OwnerIndex=235|IndexInSheet=13|OwnerPartId=-1|Location.X=1357|Location.Y=842|Color=8388608|FontID=1|IsHidden=T|Text=0603|Name=Supplier Device Package
|RECORD=41|OwnerIndex=235|IndexInSheet=14|OwnerPartId=-1|Location.X=1357|Location.Y=842|Color=8388608|FontID=1|IsHidden=T|Text=2|Name=Number of Terminations
|RECORD=41|OwnerIndex=235|IndexInSheet=15|OwnerPartId=-1|Location.X=1357|Location.Y=842|Color=8388608|FontID=1|IsHidden=T|Text=ChipResistor-SurfaceMount|Name=Family
|RECORD=41|OwnerIndex=235|IndexInSheet=16|OwnerPartId=-1|Location.X=1357|Location.Y=842|Color=8388608|FontID=1|IsHidden=T|Text=0603|Name=Package Reference
|RECORD=41|OwnerIndex=235|IndexInSheet=17|OwnerPartId=-1|Location.X=1357|Location.Y=842|Color=8388608|FontID=1|IsHidden=T|Text=0.061"Lx0.031"W(1.55mmx0.80mm)|Name=Size / Dimension
|RECORD=41|OwnerIndex=235|IndexInSheet=18|OwnerPartId=-1|Location.X=1357|Location.Y=842|Color=8388608|FontID=1|IsHidden=T|Text=SurfaceMount|Name=Mounting Technology
|RECORD=41|OwnerIndex=235|IndexInSheet=19|OwnerPartId=-1|Location.X=1357|Location.Y=842|Color=8388608|FontID=1|IsHidden=T|Text=2-Pin Surface Mount Device, Body 1.55 x 0.8 mm|Name=Package Description
|RECORD=41|OwnerIndex=235|IndexInSheet=20|OwnerPartId=-1|Location.X=1357|Location.Y=842|Color=8388608|FontID=1|IsHidden=T|Text=-55°C~155°C|Name=Operating Temperature
|RECORD=41|OwnerIndex=235|IndexInSheet=21|OwnerPartId=-1|Location.X=1357|Location.Y=842|Color=8388608|FontID=1|IsHidden=T|Text=±100ppm/°C|Name=Temperature Coefficient
|RECORD=41|OwnerIndex=235|IndexInSheet=22|OwnerPartId=-1|Location.X=1357|Location.Y=842|Color=8388608|FontID=1|IsHidden=T|Text=ThickFilm|Name=Composition
|RECORD=41|OwnerIndex=235|IndexInSheet=23|OwnerPartId=-1|Location.X=1357|Location.Y=842|Color=8388608|FontID=1|IsHidden=T|Text=0.1W,1/10W|Name=Power (Watts)
|RECORD=41|OwnerIndex=235|IndexInSheet=24|OwnerPartId=-1|Location.X=1357|Location.Y=842|Color=8388608|FontID=1|IsHidden=T|Text=Stackpole-Electronics-Inc.|Name=Manufacturer
|RECORD=41|OwnerIndex=235|IndexInSheet=25|OwnerPartId=-1|Location.X=1357|Location.Y=842|Color=8388608|FontID=1|IsHidden=T|Text=Resistors|Name=Category
|RECORD=34|OwnerIndex=235|IndexInSheet=-1|OwnerPartId=-1|Location.X=1363|Location.Y=821|Color=8388608|FontID=1|Text=R37|Name=Designator|ReadOnlyState=1
|RECORD=41|OwnerIndex=235|IndexInSheet=-1|OwnerPartId=-1|Location.X=1363|Location.Y=811|Color=8388608|FontID=1|Text=10K|Name=Comment
|RECORD=44|OwnerIndex=235
|RECORD=45|OwnerIndex=266|IndexInSheet=-1|Description=Chip Resistor, 2-Leads, Body 1.7x0.95mm, IPC High Density|UseComponentLibrary=T|ModelName=RESC1608X55X30LL15T20|ModelType=PCBLIB|DatafileCount=1|ModelDatafileEntity0=RESC1608X55X30LL15T20|ModelDatafileKind0=PCBLib|IsCurrent=T|DatalinksLocked=T|DatabaseDatalinksLocked=T
|RECORD=46|OwnerIndex=267
|RECORD=48|OwnerIndex=267
|RECORD=41|OwnerIndex=269|IndexInSheet=-1|OwnerPartId=-1|Color=8388608|FontID=1|Text=2D|Name=Available Preview Images
|RECORD=45|OwnerIndex=266|IndexInSheet=-1|Description=Chip Resistor, 2-Leads, Body 1.7x0.95mm, IPC Low Density|UseComponentLibrary=T|ModelName=RESC1608X55X30ML15T20|ModelType=PCBLIB|DatafileCount=1|ModelDatafileEntity0=RESC1608X55X30ML15T20|ModelDatafileKind0=PCBLib|DatalinksLocked=T|DatabaseDatalinksLocked=T
|RECORD=46|OwnerIndex=271
|RECORD=48|OwnerIndex=271
|RECORD=41|OwnerIndex=273|IndexInSheet=-1|OwnerPartId=-1|Color=8388608|FontID=1|Text=2D|Name=Available Preview Images
|RECORD=45|OwnerIndex=266|IndexInSheet=-1|Description=Chip Resistor, 2-Leads, Body 1.7x0.95mm, IPC Medium Density|UseComponentLibrary=T|ModelName=RESC1608X55X30NL15T20|ModelType=PCBLIB|DatafileCount=1|ModelDatafileEntity0=RESC1608X55X30NL15T20|ModelDatafileKind0=PCBLib|DatalinksLocked=T|DatabaseDatalinksLocked=T
|RECORD=46|OwnerIndex=275
|RECORD=48|OwnerIndex=275
|RECORD=41|OwnerIndex=277|IndexInSheet=-1|OwnerPartId=-1|Color=8388608|FontID=1|Text=2D|Name=Available Preview Images
|RECORD=41|IndexInSheet=27|OwnerPartId=-1|Color=8388608|FontID=1|IsHidden=T|Name=ConfigurationParameters|ReadOnlyState=1
|RECORD=41|IndexInSheet=28|OwnerPartId=-1|Color=8388608|FontID=1|IsHidden=T|Name=ConfiguratorName|ReadOnlyState=1
|RECORD=41|IndexInSheet=29|OwnerPartId=-1|Color=8388608|FontID=1|IsHidden=T|Name=VersionControl_RevNumber|ReadOnlyState=1
|RECORD=41|IndexInSheet=30|OwnerPartId=-1|Color=8388608|FontID=1|IsHidden=T|Name=IsUserConfigurable|ReadOnlyState=1
|RECORD=41|IndexInSheet=31|OwnerPartId=-1|Color=8388608|FontID=1|IsHidden=T|Name=VersionControl_ProjFolderRevNumber|ReadOnlyState=1
|RECORD=41|IndexInSheet=32|OwnerPartId=-1|Color=8388608|FontID=1|IsHidden=T|Text=|Name=SPICEModelCache|ReadOnlyState=1
|RECORD=4|IndexInSheet=33|OwnerPartId=-1|Location.X=1460|Location.Y=856|Color=8388608|FontID=7|Text=EEPROM
|RECORD=1|LibReference=d58e2f6669bc67e6a2bc6a28610ca79|ComponentDescription=SENSOR PRESSURE HUMIDITY TEMP|PartCount=2|DisplayModeCount=1|IndexInSheet=34|OwnerPartId=-1|Location.X=830|Location.Y=320|CurrentPartId=1|LibraryPath=*|SourceLibraryName=Altium Content Vault|TargetFileName=*|AreaColor=11599871|Color=128|PartIDLocked=T|DesignItemId=CMP-2000-05073-3|AllPinCount=8
|RECORD=14|OwnerIndex=286|IsNotAccesible=T|OwnerPartId=1|Location.X=850|Location.Y=250|Corner.X=950|Corner.Y=330|LineWidth=1|Color=128|AreaColor=11599871|IsSolid=T
|RECORD=2|OwnerIndex=286|OwnerPartId=1|Electrical=7|PinConglomerate=58|PinLength=20|Location.X=850|Location.Y=320|Name=VDD|Designator=8|PinPropagationDelay=0.000000E+000
|RECORD=2|OwnerIndex=286|OwnerPartId=1|Electrical=7|PinConglomerate=58|PinLength=20|Location.X=850|Location.Y=310|Name=VDDIO|Designator=6|PinPropagationDelay=0.000000E+000
|RECORD=2|OwnerIndex=286|OwnerPartId=1|PinConglomerate=56|PinLength=20|Location.X=950|Location.Y=290|Name=C\S\|Designator=2|PinPropagationDelay=0.000000E+000
|RECORD=2|OwnerIndex=286|OwnerPartId=1|SymBol_InnerEdge=3|PinConglomerate=56|PinLength=20|Location.X=950|Location.Y=320|Name=SCK|Designator=4|PinPropagationDelay=0.000000E+000
|RECORD=2|OwnerIndex=286|OwnerPartId=1|Electrical=1|PinConglomerate=56|PinLength=20|Location.X=950|Location.Y=310|Name=SDI|Designator=3|PinPropagationDelay=0.000000E+000
|RECORD=2|OwnerIndex=286|OwnerPartId=1|Electrical=1|PinConglomerate=56|PinLength=20|Location.X=950|Location.Y=300|Name=SDO|Designator=5|PinPropagationDelay=0.000000E+000
|RECORD=2|OwnerIndex=286|OwnerPartId=1|Electrical=7|PinConglomerate=56|PinLength=20|Location.X=950|Location.Y=270|Name=GND|Designator=1|PinPropagationDelay=0.000000E+000
|RECORD=2|OwnerIndex=286|OwnerPartId=1|Electrical=7|PinConglomerate=56|PinLength=20|Location.X=950|Location.Y=260|Name=GND|Designator=7|PinPropagationDelay=0.000000E+000
|RECORD=41|OwnerIndex=286|IndexInSheet=9|OwnerPartId=-1|Location.X=828|Location.Y=330|Color=8388608|FontID=1|IsHidden=T|Text=Temperature|Name=Sensor Type
|RECORD=41|OwnerIndex=286|IndexInSheet=10|OwnerPartId=-1|Location.X=828|Location.Y=330|Color=8388608|FontID=1|IsHidden=T|Text=-40°C|Name=Min Operating Temperature
|RECORD=41|OwnerIndex=286|IndexInSheet=11|OwnerPartId=-1|Location.X=828|Location.Y=330|Color=8388608|FontID=1|IsHidden=T|Text=3%|Name=Accuracy
|RECORD=41|OwnerIndex=286|IndexInSheet=12|OwnerPartId=-1|Location.X=828|Location.Y=330|Color=8388608|FontID=1|IsHidden=T|Text=85°C|Name=Max Operating Temperature
|RECORD=41|OwnerIndex=286|IndexInSheet=13|OwnerPartId=-1|Location.X=828|Location.Y=330|Color=8388608|FontID=1|IsHidden=T|Text=LGA|Name=Case/Package
|RECORD=41|OwnerIndex=286|IndexInSheet=14|OwnerPartId=-1|Location.X=828|Location.Y=330|Color=8388608|FontID=1|IsHidden=T|Text=Cut Tape|Name=Packaging
|RECORD=41|OwnerIndex=286|IndexInSheet=15|OwnerPartId=-1|Location.X=828|Location.Y=330|Color=8388608|FontID=1|IsHidden=T|Text=Surface Mount|Name=Mount
|RECORD=41|OwnerIndex=286|IndexInSheet=16|OwnerPartId=-1|Location.X=828|Location.Y=330|Color=8388608|FontID=1|IsHidden=T|Text=1s|Name=Response Time
|RECORD=41|OwnerIndex=286|IndexInSheet=17|OwnerPartId=-1|Location.X=828|Location.Y=330|Color=8388608|FontID=1|IsHidden=T|Text=SPI|Name=Output Type
|RECORD=41|OwnerIndex=286|IndexInSheet=18|OwnerPartId=-1|Location.X=828|Location.Y=330|Color=8388608|FontID=1|IsHidden=T|Text=Lead Free|Name=Lead Free
|RECORD=41|OwnerIndex=286|IndexInSheet=19|OwnerPartId=-1|Location.X=828|Location.Y=330|Color=8388608|FontID=1|IsHidden=T|Text=8|Name=Number of Pins
|RECORD=34|OwnerIndex=286|IndexInSheet=-1|OwnerPartId=-1|Location.X=850|Location.Y=330|Color=8388608|FontID=1|Text=U14|Name=Designator|ReadOnlyState=1
|RECORD=41|OwnerIndex=286|IndexInSheet=-1|OwnerPartId=1|Location.X=850|Location.Y=240|Color=8388608|FontID=1|Text=BME280|Name=Comment
|RECORD=44|OwnerIndex=286
|RECORD=45|OwnerIndex=317|IndexInSheet=-1|UseComponentLibrary=T|ModelName=FP-BME280-MFG|ModelType=PCBLIB|DatafileCount=1|ModelDatafileEntity0=FP-BME280-MFG|ModelDatafileKind0=PCBLib|IsCurrent=T|DatalinksLocked=T|DatabaseDatalinksLocked=T
|RECORD=46|OwnerIndex=318
|RECORD=48|OwnerIndex=318
|RECORD=17|IndexInSheet=35|OwnerPartId=-1|Style=4|ShowNetName=T|Location.X=800|Location.Y=170|Orientation=3|Color=128|FontID=1|Text=GND
|RECORD=17|IndexInSheet=36|OwnerPartId=-1|Style=4|ShowNetName=T|Location.X=750|Location.Y=170|Orientation=3|Color=128|FontID=1|Text=GND
|RECORD=1|LibReference=CAP|ComponentDescription=C0603X104K5RACAUTO|PartCount=2|DisplayModeCount=2|IndexInSheet=37|OwnerPartId=-1|Location.X=790|Location.Y=200|Orientation=1|CurrentPartId=1|SourceLibraryName=Altium Content Vault|TargetFileName=*|AreaColor=11599871|Color=128|PartIDLocked=F|DesignItemId=CMP-2006-00003-1|AllPinCount=2
|RECORD=2|OwnerIndex=323|OwnerPartId=1|OwnerPartDisplayMode=1|FormalType=1|Electrical=4|PinConglomerate=35|PinLength=10|Location.X=800|Location.Y=200|Name=1|Designator=1|PinPropagationDelay=0.000000E+000
|RECORD=2|OwnerIndex=323|OwnerPartId=1|OwnerPartDisplayMode=1|FormalType=1|Electrical=4|PinConglomerate=33|PinLength=10|Location.X=800|Location.Y=210|Name=2|Designator=2|PinPropagationDelay=0.000000E+000
|RECORD=13|OwnerIndex=323|IsNotAccesible=T|IndexInSheet=2|OwnerPartId=1|OwnerPartDisplayMode=1|Location.X=808|Location.Y=200|Corner.X=792|Corner.Y=200|LineWidth=1|Color=16711680
|RECORD=13|OwnerIndex=323|IsNotAccesible=T|IndexInSheet=3|OwnerPartId=1|OwnerPartDisplayMode=1|Location.X=800|Location.Y=204|Corner.X=800|Corner.Y=210|LineWidth=1|Color=16711680
|RECORD=12|OwnerIndex=323|IsNotAccesible=T|IndexInSheet=4|OwnerPartId=1|OwnerPartDisplayMode=1|Location.X=800|Location.Y=220|Radius=16|LineWidth=1|StartAngle=241.000|EndAngle=270.000|Color=16711680
|RECORD=12|OwnerIndex=323|IsNotAccesible=T|IndexInSheet=5|OwnerPartId=1|OwnerPartDisplayMode=1|Location.X=800|Location.Y=220|Radius=16|LineWidth=1|StartAngle=270.000|EndAngle=299.000|Color=16711680
|RECORD=2|OwnerIndex=323|OwnerPartId=1|FormalType=1|Electrical=4|PinConglomerate=35|PinLength=10|Location.X=800|Location.Y=200|Name=1|Designator=1|PinPropagationDelay=0.000000E+000
|RECORD=2|OwnerIndex=323|OwnerPartId=1|FormalType=1|Electrical=4|PinConglomerate=33|PinLength=10|Location.X=800|Location.Y=210|Name=2|Designator=2|PinPropagationDelay=0.000000E+000
|RECORD=13|OwnerIndex=323|IsNotAccesible=T|IndexInSheet=8|OwnerPartId=1|Location.X=792|Location.Y=207|Corner.X=808|Corner.Y=207|LineWidth=1|Color=16711680
|RECORD=13|OwnerIndex=323|IsNotAccesible=T|IndexInSheet=9|OwnerPartId=1|Location.X=808|Location.Y=203|Corner.X=792|Corner.Y=203|LineWidth=1|Color=16711680
|RECORD=6|OwnerIndex=323|IsNotAccesible=T|IndexInSheet=10|OwnerPartId=1|LineWidth=1|Color=16711680|LocationCount=2|X1=800|Y1=200|X2=800|Y2=203
|RECORD=6|OwnerIndex=323|IsNotAccesible=T|IndexInSheet=11|OwnerPartId=1|LineWidth=1|Color=16711680|LocationCount=2|X1=800|Y1=210|X2=800|Y2=207
|RECORD=41|OwnerIndex=323|IndexInSheet=12|OwnerPartId=-1|Location.X=791|Location.Y=222|Color=8388608|FontID=1|IsHidden=T|Text=Kemet|Name=Manufacturer
|RECORD=41|OwnerIndex=323|IndexInSheet=13|OwnerPartId=-1|Location.X=791|Location.Y=222|Color=8388608|FontID=1|IsHidden=T|Text=C0603X104K5RACAUTO|Name=Part Number
|RECORD=34|OwnerIndex=323|IndexInSheet=-1|OwnerPartId=-1|Location.X=809|Location.Y=201|Color=8388608|FontID=1|Text=C31|Name=Designator|ReadOnlyState=1
|RECORD=41|OwnerIndex=323|IndexInSheet=-1|OwnerPartId=-1|Location.X=809|Location.Y=191|Color=8388608|FontID=1|Text=0.1uF|Name=Comment
|RECORD=44|OwnerIndex=323
|RECORD=45|OwnerIndex=344|IndexInSheet=-1|Description=Chip Capacitor, 2-Leads, Body 1.60x0.80mm, IPC Low Density|UseComponentLibrary=T|ModelName=CAPC1608X87X45ML20T05|ModelType=PCBLIB|DatafileCount=1|ModelDatafileEntity0=CAPC1608X87X45ML20T05|ModelDatafileKind0=PCBLib|IsCurrent=T|DatalinksLocked=T|DatabaseDatalinksLocked=T
|RECORD=46|OwnerIndex=345
|RECORD=48|OwnerIndex=345
|RECORD=41|OwnerIndex=347|IndexInSheet=-1|OwnerPartId=-1|Color=8388608|FontID=1|Text=2D|Name=Available Preview Images
|RECORD=45|OwnerIndex=344|IndexInSheet=-1|Description=Chip Capacitor, 2-Leads, Body 1.60x0.80mm, IPC High Density|UseComponentLibrary=T|ModelName=CAPC1608X87X45LL20T05|ModelType=PCBLIB|DatafileCount=1|ModelDatafileEntity0=CAPC1608X87X45LL20T05|ModelDatafileKind0=PCBLib|DatalinksLocked=T|DatabaseDatalinksLocked=T
|RECORD=46|OwnerIndex=349
|RECORD=48|OwnerIndex=349
|RECORD=41|OwnerIndex=351|IndexInSheet=-1|OwnerPartId=-1|Color=8388608|FontID=1|Text=2D|Name=Available Preview Images
|RECORD=45|OwnerIndex=344|IndexInSheet=-1|Description=Chip Capacitor, 2-Leads, Body 1.60x0.80mm, IPC Medium Density|UseComponentLibrary=T|ModelName=CAPC1608X87X45NL20T05|ModelType=PCBLIB|DatafileCount=1|ModelDatafileEntity0=CAPC1608X87X45NL20T05|ModelDatafileKind0=PCBLib|DatalinksLocked=T|DatabaseDatalinksLocked=T
|RECORD=46|OwnerIndex=353
|RECORD=48|OwnerIndex=353
|RECORD=41|OwnerIndex=355|IndexInSheet=-1|OwnerPartId=-1|Color=8388608|FontID=1|Text=2D|Name=Available Preview Images
|RECORD=1|LibReference=CAP|ComponentDescription=C0603X104K5RACAUTO|PartCount=2|DisplayModeCount=2|IndexInSheet=38|OwnerPartId=-1|Location.X=740|Location.Y=200|Orientation=1|CurrentPartId=1|SourceLibraryName=Altium Content Vault|TargetFileName=*|AreaColor=11599871|Color=128|PartIDLocked=F|DesignItemId=CMP-2006-00003-1|AllPinCount=2
|RECORD=2|OwnerIndex=357|OwnerPartId=1|OwnerPartDisplayMode=1|FormalType=1|Electrical=4|PinConglomerate=35|PinLength=10|Location.X=750|Location.Y=200|Name=1|Designator=1|PinPropagationDelay=0.000000E+000
|RECORD=2|OwnerIndex=357|OwnerPartId=1|OwnerPartDisplayMode=1|FormalType=1|Electrical=4|PinConglomerate=33|PinLength=10|Location.X=750|Location.Y=210|Name=2|Designator=2|PinPropagationDelay=0.000000E+000
|RECORD=13|OwnerIndex=357|IsNotAccesible=T|IndexInSheet=2|OwnerPartId=1|OwnerPartDisplayMode=1|Location.X=758|Location.Y=200|Corner.X=742|Corner.Y=200|LineWidth=1|Color=16711680
|RECORD=13|OwnerIndex=357|IsNotAccesible=T|IndexInSheet=3|OwnerPartId=1|OwnerPartDisplayMode=1|Location.X=750|Location.Y=204|Corner.X=750|Corner.Y=210|LineWidth=1|Color=16711680
|RECORD=12|OwnerIndex=357|IsNotAccesible=T|IndexInSheet=4|OwnerPartId=1|OwnerPartDisplayMode=1|Location.X=750|Location.Y=220|Radius=16|LineWidth=1|StartAngle=241.000|EndAngle=270.000|Color=16711680
|RECORD=12|OwnerIndex=357|IsNotAccesible=T|IndexInSheet=5|OwnerPartId=1|OwnerPartDisplayMode=1|Location.X=750|Location.Y=220|Radius=16|LineWidth=1|StartAngle=270.000|EndAngle=299.000|Color=16711680
|RECORD=2|OwnerIndex=357|OwnerPartId=1|FormalType=1|Electrical=4|PinConglomerate=35|PinLength=10|Location.X=750|Location.Y=200|Name=1|Designator=1|PinPropagationDelay=0.000000E+000
|RECORD=2|OwnerIndex=357|OwnerPartId=1|FormalType=1|Electrical=4|PinConglomerate=33|PinLength=10|Location.X=750|Location.Y=210|Name=2|Designator=2|PinPropagationDelay=0.000000E+000
|RECORD=13|OwnerIndex=357|IsNotAccesible=T|IndexInSheet=8|OwnerPartId=1|Location.X=742|Location.Y=207|Corner.X=758|Corner.Y=207|LineWidth=1|Color=16711680
|RECORD=13|OwnerIndex=357|IsNotAccesible=T|IndexInSheet=9|OwnerPartId=1|Location.X=758|Location.Y=203|Corner.X=742|Corner.Y=203|LineWidth=1|Color=16711680
|RECORD=6|OwnerIndex=357|IsNotAccesible=T|IndexInSheet=10|OwnerPartId=1|LineWidth=1|Color=16711680|LocationCount=2|X1=750|Y1=200|X2=750|Y2=203
|RECORD=6|OwnerIndex=357|IsNotAccesible=T|IndexInSheet=11|OwnerPartId=1|LineWidth=1|Color=16711680|LocationCount=2|X1=750|Y1=210|X2=750|Y2=207
|RECORD=41|OwnerIndex=357|IndexInSheet=12|OwnerPartId=-1|Location.X=741|Location.Y=222|Color=8388608|FontID=1|IsHidden=T|Text=Kemet|Name=Manufacturer
|RECORD=41|OwnerIndex=357|IndexInSheet=13|OwnerPartId=-1|Location.X=741|Location.Y=222|Color=8388608|FontID=1|IsHidden=T|Text=C0603X104K5RACAUTO|Name=Part Number
|RECORD=34|OwnerIndex=357|IndexInSheet=-1|OwnerPartId=-1|Location.X=759|Location.Y=201|Color=8388608|FontID=1|Text=C30|Name=Designator|ReadOnlyState=1
|RECORD=41|OwnerIndex=357|IndexInSheet=-1|OwnerPartId=-1|Location.X=759|Location.Y=191|Color=8388608|FontID=1|Text=0.1uF|Name=Comment
|RECORD=44|OwnerIndex=357
|RECORD=45|OwnerIndex=378|IndexInSheet=-1|Description=Chip Capacitor, 2-Leads, Body 1.60x0.80mm, IPC Low Density|UseComponentLibrary=T|ModelName=CAPC1608X87X45ML20T05|ModelType=PCBLIB|DatafileCount=1|ModelDatafileEntity0=CAPC1608X87X45ML20T05|ModelDatafileKind0=PCBLib|IsCurrent=T|DatalinksLocked=T|DatabaseDatalinksLocked=T
|RECORD=46|OwnerIndex=379
|RECORD=48|OwnerIndex=379
|RECORD=41|OwnerIndex=381|IndexInSheet=-1|OwnerPartId=-1|Color=8388608|FontID=1|Text=2D|Name=Available Preview Images
|RECORD=45|OwnerIndex=378|IndexInSheet=-1|Description=Chip Capacitor, 2-Leads, Body 1.60x0.80mm, IPC High Density|UseComponentLibrary=T|ModelName=CAPC1608X87X45LL20T05|ModelType=PCBLIB|DatafileCount=1|ModelDatafileEntity0=CAPC1608X87X45LL20T05|ModelDatafileKind0=PCBLib|DatalinksLocked=T|DatabaseDatalinksLocked=T
|RECORD=46|OwnerIndex=383
|RECORD=48|OwnerIndex=383
|RECORD=41|OwnerIndex=385|IndexInSheet=-1|OwnerPartId=-1|Color=8388608|FontID=1|Text=2D|Name=Available Preview Images
|RECORD=45|OwnerIndex=378|IndexInSheet=-1|Description=Chip Capacitor, 2-Leads, Body 1.60x0.80mm, IPC Medium Density|UseComponentLibrary=T|ModelName=CAPC1608X87X45NL20T05|ModelType=PCBLIB|DatafileCount=1|ModelDatafileEntity0=CAPC1608X87X45NL20T05|ModelDatafileKind0=PCBLib|DatalinksLocked=T|DatabaseDatalinksLocked=T
|RECORD=46|OwnerIndex=387
|RECORD=48|OwnerIndex=387
|RECORD=41|OwnerIndex=389|IndexInSheet=-1|OwnerPartId=-1|Color=8388608|FontID=1|Text=2D|Name=Available Preview Images
|RECORD=17|IndexInSheet=39|OwnerPartId=-1|ShowNetName=T|Location.X=800|Location.Y=370|Orientation=1|Color=128|FontID=1|Text=+3.3V
|RECORD=17|IndexInSheet=40|OwnerPartId=-1|ShowNetName=T|Location.X=750|Location.Y=370|Orientation=1|Color=128|FontID=1|Text=+3.3V
|RECORD=17|IndexInSheet=41|OwnerPartId=-1|ShowNetName=T|Location.X=1050|Location.Y=320|Color=255|FontID=1|Text=SCL|IsCrossSheetConnector=T
|RECORD=17|IndexInSheet=42|OwnerPartId=-1|ShowNetName=T|Location.X=1050|Location.Y=310|Color=255|FontID=1|Text=SDA|IsCrossSheetConnector=T
|RECORD=17|IndexInSheet=43|OwnerPartId=-1|ShowNetName=T|Location.X=1010|Location.Y=370|Orientation=1|Color=128|FontID=1|Text=+3.3V
|RECORD=17|IndexInSheet=44|OwnerPartId=-1|Style=4|ShowNetName=T|Location.X=1010|Location.Y=170|Orientation=3|Color=128|FontID=1|Text=GND
|RECORD=17|IndexInSheet=45|OwnerPartId=-1|Style=4|ShowNetName=T|Location.X=1050|Location.Y=170|Orientation=3|Color=128|FontID=1|Text=GND
|RECORD=4|IndexInSheet=46|OwnerPartId=-1|Location.X=800|Location.Y=410|Color=8388608|FontID=7|Text=ENVIRONMENT (0x76)
|RECORD=4|IndexInSheet=47|OwnerPartId=-1|Location.X=1360|Location.Y=440|Color=8388608|FontID=7|Text=IMU (0x29)
|RECORD=17|IndexInSheet=48|OwnerPartId=-1|ShowNetName=T|Location.X=1580|Location.Y=920|Orientation=3|Color=255|FontID=1|Text=SCL|IsCrossSheetConnector=T
|RECORD=17|IndexInSheet=49|OwnerPartId=-1|ShowNetName=T|Location.X=1530|Location.Y=920|Orientation=3|Color=255|FontID=1|Text=SDA|IsCrossSheetConnector=T
|RECORD=17|IndexInSheet=50|OwnerPartId=-1|ShowNetName=T|Location.X=1580|Location.Y=1030|Orientation=1|Color=128|FontID=1|Text=+3.3V
|RECORD=17|IndexInSheet=51|OwnerPartId=-1|ShowNetName=T|Location.X=1530|Location.Y=1030|Orientation=1|Color=128|FontID=1|Text=+3.3V
|RECORD=1|LibReference=RES-2|ComponentDescription=Precision Thick Film Chip Resistor, 4.7 KOhm, +/- 1%, -55 to 155 degC, 0603 (1608 Metric), RoHS, Tape and Reel ERJ-3EKF4701V|PartCount=2|DisplayModeCount=1|IndexInSheet=52|OwnerPartId=-1|Location.X=1580|Location.Y=970|Orientation=1|CurrentPartId=1|LibraryPath=*|SourceLibraryName=Altium Content Vault|TargetFileName=*|AreaColor=11599871|Color=128|PartIDLocked=T|DesignItemId=CMP-1012-00586-3|AllPinCount=2
|RECORD=2|OwnerIndex=404|OwnerPartId=1|FormalType=1|Electrical=4|PinConglomerate=33|PinLength=10|Location.X=1580|Location.Y=990|Name=2|Designator=2|PinPropagationDelay=0.000000E+000
|RECORD=2|OwnerIndex=404|OwnerPartId=1|FormalType=1|Electrical=4|PinConglomerate=35|PinLength=10|Location.X=1580|Location.Y=970|Name=1|Designator=1|PinPropagationDelay=0.000000E+000
|RECORD=6|OwnerIndex=404|IsNotAccesible=T|IndexInSheet=2|OwnerPartId=1|LineWidth=1|Color=16711680|LocationCount=10|X1=1580|Y1=990|X2=1580|Y2=986|X3=1582|Y3=985|X4=1578|Y4=983|X5=1582|Y5=981|X6=1578|Y6=979|X7=1582|Y7=977|X8=1578|Y8=975|X9=1580|Y9=974|X10=1580|Y10=970
|RECORD=41|OwnerIndex=404|IndexInSheet=3|OwnerPartId=-1|Location.X=1577|Location.Y=1002|Color=8388608|FontID=1|IsHidden=T|Text=220 Ohm|Name=Resistance
|RECORD=41|OwnerIndex=404|IndexInSheet=4|OwnerPartId=-1|Location.X=1577|Location.Y=1002|Color=8388608|FontID=1|IsHidden=T|Text=0603|Name=PackageReference
|RECORD=41|OwnerIndex=404|IndexInSheet=5|OwnerPartId=-1|Location.X=1577|Location.Y=1002|Color=8388608|FontID=1|IsHidden=T|Text=50 V|Name=Voltage Rating
|RECORD=41|OwnerIndex=404|IndexInSheet=6|OwnerPartId=-1|Location.X=1577|Location.Y=1002|Color=8388608|FontID=1|IsHidden=T|Text=125 degC|Name=Max Operating Temperature
|RECORD=41|OwnerIndex=404|IndexInSheet=7|OwnerPartId=-1|Location.X=1577|Location.Y=1002|Color=8388608|FontID=1|IsHidden=T|Text=4|Name=Elements
|RECORD=41|OwnerIndex=404|IndexInSheet=8|OwnerPartId=-1|Location.X=1577|Location.Y=1002|Color=8388608|FontID=1|IsHidden=T|Text=No SVHC|Name=REACH SVHC
|RECORD=41|OwnerIndex=404|IndexInSheet=9|OwnerPartId=-1|Location.X=1577|Location.Y=1002|Color=8388608|FontID=1|IsHidden=T|Text=0.063 inch|Name=Width
|RECORD=41|OwnerIndex=404|IndexInSheet=10|OwnerPartId=-1|Location.X=1577|Location.Y=1002|Color=8388608|FontID=1|IsHidden=T|Text=1205|Name=Case\Package
|RECORD=41|OwnerIndex=404|IndexInSheet=11|OwnerPartId=-1|Location.X=1577|Location.Y=1002|Color=8388608|FontID=1|IsHidden=T|Text=0.126 inch|Name=Length
|RECORD=41|OwnerIndex=404|IndexInSheet=12|OwnerPartId=-1|Location.X=1577|Location.Y=1002|Color=8388608|FontID=1|IsHidden=T|Text=0.024 inch|Name=Height
|RECORD=41|OwnerIndex=404|IndexInSheet=13|OwnerPartId=-1|Location.X=1577|Location.Y=1002|Color=8388608|FontID=1|IsHidden=T|Text=Surface Mount|Name=Mount
|RECORD=41|OwnerIndex=404|IndexInSheet=14|OwnerPartId=-1|Location.X=1577|Location.Y=1002|Color=8388608|FontID=1|IsHidden=T|Text=1|Name=Package Quantity
|RECORD=41|OwnerIndex=404|IndexInSheet=15|OwnerPartId=-1|Location.X=1577|Location.Y=1002|Color=8388608|FontID=1|IsHidden=T|Text=Apr-15|Name=DatasheetVersion
|RECORD=41|OwnerIndex=404|IndexInSheet=16|OwnerPartId=-1|Location.X=1577|Location.Y=1002|Color=8388608|FontID=1|IsHidden=T|Text=Manufacturer URL|Name=ComponentLink1Description
|RECORD=41|OwnerIndex=404|IndexInSheet=17|OwnerPartId=-1|Location.X=1577|Location.Y=1002|Color=8388608|FontID=1|IsHidden=T|Text=-55 degC|Name=Min Operating Temperature
|RECORD=41|OwnerIndex=404|IndexInSheet=18|OwnerPartId=-1|Location.X=1577|Location.Y=1002|Color=8388608|FontID=1|IsHidden=T|Text=Tape and Reel|Name=Packaging
|RECORD=41|OwnerIndex=404|IndexInSheet=19|OwnerPartId=-1|Location.X=1577|Location.Y=1002|Color=8388608|FontID=1|IsHidden=T|Text=No|Name=Radiation Hardening
|RECORD=41|OwnerIndex=404|IndexInSheet=20|OwnerPartId=-1|Location.X=1577|Location.Y=1002|Color=8388608|FontID=8|IsHidden=T|Text=http://industrial.panasonic.com/cdbs/www-data/pdf/RDA0000/AOA0000C86.pdf|Name=ComponentLink2URL
|RECORD=41|OwnerIndex=404|IndexInSheet=21|OwnerPartId=-1|Location.X=1577|Location.Y=1002|Color=8388608|FontID=1|IsHidden=T|Text=3216|Name=Case Code (Metric)
|RECORD=41|OwnerIndex=404|IndexInSheet=22|OwnerPartId=-1|Location.X=1577|Location.Y=1002|Color=8388608|FontID=1|IsHidden=T|Text=8|Name=Pins
|RECORD=41|OwnerIndex=404|IndexInSheet=23|OwnerPartId=-1|Location.X=1577|Location.Y=1002|Color=8388608|FontID=1|IsHidden=T|Text=1206|Name=Case Code (Imperial)
|RECORD=41|OwnerIndex=404|IndexInSheet=24|OwnerPartId=-1|Location.X=1577|Location.Y=1002|Color=8388608|FontID=1|IsHidden=T|Text=Thick Film|Name=Type (Resistor)
|RECORD=41|OwnerIndex=404|IndexInSheet=25|OwnerPartId=-1|Location.X=1577|Location.Y=1002|Color=8388608|FontID=1|IsHidden=T|Text=true|Name=RoHSCompliant
|RECORD=41|OwnerIndex=404|IndexInSheet=26|OwnerPartId=-1|Location.X=1577|Location.Y=1002|Color=8388608|FontID=1|IsHidden=T|Text=5%|Name=Tolerance
|RECORD=41|OwnerIndex=404|IndexInSheet=27|OwnerPartId=-1|Location.X=1577|Location.Y=1002|Color=8388608|FontID=1|IsHidden=T|Text=Datasheet|Name=ComponentLink2Description
|RECORD=41|OwnerIndex=404|IndexInSheet=28|OwnerPartId=-1|Location.X=1577|Location.Y=1002|Color=8388608|FontID=1|IsHidden=T|Text=2-Pin Surface Mount Device, Body 1.6 x 0.85 mm|Name=PackageDescription
|RECORD=41|OwnerIndex=404|IndexInSheet=29|OwnerPartId=-1|Location.X=1577|Location.Y=1002|Color=8388608|FontID=8|IsHidden=T|Text=http://www.panasonic.com/|Name=ComponentLink1URL
|RECORD=41|OwnerIndex=404|IndexInSheet=30|OwnerPartId=-1|Location.X=1577|Location.Y=1002|Color=8388608|FontID=1|IsHidden=T|Text=250 mW|Name=Power Rating
|RECORD=34|OwnerIndex=404|IndexInSheet=-1|OwnerPartId=-1|Location.X=1583|Location.Y=981|Color=8388608|FontID=1|Text=R27|Name=Designator|ReadOnlyState=1
|RECORD=41|OwnerIndex=404|IndexInSheet=-1|OwnerPartId=-1|Location.X=1583|Location.Y=971|Color=8388608|FontID=1|Text=4.7K|Name=Comment
|RECORD=44|OwnerIndex=404
|RECORD=45|OwnerIndex=440|IndexInSheet=-1|Description=Chip Resistor, 2-Leads, Body 1.75x0.95mm, IPC Medium Density|UseComponentLibrary=T|ModelName=RESC1608X55X30NL15T15|ModelType=PCBLIB|DatafileCount=1|ModelDatafileEntity0=RESC1608X55X30NL15T15|ModelDatafileKind0=PCBLib|IsCurrent=T|DatalinksLocked=T|DatabaseDatalinksLocked=T
|RECORD=46|OwnerIndex=441
|RECORD=48|OwnerIndex=441
|RECORD=41|OwnerIndex=443|IndexInSheet=-1|OwnerPartId=-1|Color=8388608|FontID=1|IsHidden=T|Text=2D|Name=Available Preview Images
|RECORD=45|OwnerIndex=440|IndexInSheet=-1|Description=Chip Resistor, 2-Leads, Body 1.75x0.95mm, IPC Low Density|UseComponentLibrary=T|ModelName=RESC1608X55X30ML15T15|ModelType=PCBLIB|DatafileCount=1|ModelDatafileEntity0=RESC1608X55X30ML15T15|ModelDatafileKind0=PCBLib|DatalinksLocked=T|DatabaseDatalinksLocked=T
|RECORD=46|OwnerIndex=445
|RECORD=48|OwnerIndex=445
|RECORD=41|OwnerIndex=447|IndexInSheet=-1|OwnerPartId=-1|Color=8388608|FontID=1|IsHidden=T|Text=2D|Name=Available Preview Images
|RECORD=45|OwnerIndex=440|IndexInSheet=-1|Description=Chip Resistor, 2-Leads, Body 1.75x0.95mm, IPC High Density|UseComponentLibrary=T|ModelName=RESC1608X55X30LL15T15|ModelType=PCBLIB|DatafileCount=1|ModelDatafileEntity0=RESC1608X55X30LL15T15|ModelDatafileKind0=PCBLib|DatalinksLocked=T|DatabaseDatalinksLocked=T
|RECORD=46|OwnerIndex=449
|RECORD=48|OwnerIndex=449
|RECORD=41|OwnerIndex=451|IndexInSheet=-1|OwnerPartId=-1|Color=8388608|FontID=1|IsHidden=T|Text=2D|Name=Available Preview Images
|RECORD=1|LibReference=RES-2|ComponentDescription=Precision Thick Film Chip Resistor, 4.7 KOhm, +/- 1%, -55 to 155 degC, 0603 (1608 Metric), RoHS, Tape and Reel ERJ-3EKF4701V|PartCount=2|DisplayModeCount=1|IndexInSheet=53|OwnerPartId=-1|Location.X=1530|Location.Y=970|Orientation=1|CurrentPartId=1|LibraryPath=*|SourceLibraryName=Altium Content Vault|TargetFileName=*|AreaColor=11599871|Color=128|PartIDLocked=T|DesignItemId=CMP-1012-00586-3|AllPinCount=2
|RECORD=2|OwnerIndex=453|OwnerPartId=1|FormalType=1|Electrical=4|PinConglomerate=33|PinLength=10|Location.X=1530|Location.Y=990|Name=2|Designator=2|PinPropagationDelay=0.000000E+000
|RECORD=2|OwnerIndex=453|OwnerPartId=1|FormalType=1|Electrical=4|PinConglomerate=35|PinLength=10|Location.X=1530|Location.Y=970|Name=1|Designator=1|PinPropagationDelay=0.000000E+000
|RECORD=6|OwnerIndex=453|IsNotAccesible=T|IndexInSheet=2|OwnerPartId=1|LineWidth=1|Color=16711680|LocationCount=10|X1=1530|Y1=990|X2=1530|Y2=986|X3=1532|Y3=985|X4=1528|Y4=983|X5=1532|Y5=981|X6=1528|Y6=979|X7=1532|Y7=977|X8=1528|Y8=975|X9=1530|Y9=974|X10=1530|Y10=970
|RECORD=41|OwnerIndex=453|IndexInSheet=3|OwnerPartId=-1|Location.X=1527|Location.Y=1002|Color=8388608|FontID=1|IsHidden=T|Text=220 Ohm|Name=Resistance
|RECORD=41|OwnerIndex=453|IndexInSheet=4|OwnerPartId=-1|Location.X=1527|Location.Y=1002|Color=8388608|FontID=1|IsHidden=T|Text=0603|Name=PackageReference
|RECORD=41|OwnerIndex=453|IndexInSheet=5|OwnerPartId=-1|Location.X=1527|Location.Y=1002|Color=8388608|FontID=1|IsHidden=T|Text=50 V|Name=Voltage Rating
|RECORD=41|OwnerIndex=453|IndexInSheet=6|OwnerPartId=-1|Location.X=1527|Location.Y=1002|Color=8388608|FontID=1|IsHidden=T|Text=125 degC|Name=Max Operating Temperature
|RECORD=41|OwnerIndex=453|IndexInSheet=7|OwnerPartId=-1|Location.X=1527|Location.Y=1002|Color=8388608|FontID=1|IsHidden=T|Text=4|Name=Elements
|RECORD=41|OwnerIndex=453|IndexInSheet=8|OwnerPartId=-1|Location.X=1527|Location.Y=1002|Color=8388608|FontID=1|IsHidden=T|Text=No SVHC|Name=REACH SVHC
|RECORD=41|OwnerIndex=453|IndexInSheet=9|OwnerPartId=-1|Location.X=1527|Location.Y=1002|Color=8388608|FontID=1|IsHidden=T|Text=0.063 inch|Name=Width
|RECORD=41|OwnerIndex=453|IndexInSheet=10|OwnerPartId=-1|Location.X=1527|Location.Y=1002|Color=8388608|FontID=1|IsHidden=T|Text=1205|Name=Case\Package
|RECORD=41|OwnerIndex=453|IndexInSheet=11|OwnerPartId=-1|Location.X=1527|Location.Y=1002|Color=8388608|FontID=1|IsHidden=T|Text=0.126 inch|Name=Length
|RECORD=41|OwnerIndex=453|IndexInSheet=12|OwnerPartId=-1|Location.X=1527|Location.Y=1002|Color=8388608|FontID=1|IsHidden=T|Text=0.024 inch|Name=Height
|RECORD=41|OwnerIndex=453|IndexInSheet=13|OwnerPartId=-1|Location.X=1527|Location.Y=1002|Color=8388608|FontID=1|IsHidden=T|Text=Surface Mount|Name=Mount
|RECORD=41|OwnerIndex=453|IndexInSheet=14|OwnerPartId=-1|Location.X=1527|Location.Y=1002|Color=8388608|FontID=1|IsHidden=T|Text=1|Name=Package Quantity
|RECORD=41|OwnerIndex=453|IndexInSheet=15|OwnerPartId=-1|Location.X=1527|Location.Y=1002|Color=8388608|FontID=1|IsHidden=T|Text=Apr-15|Name=DatasheetVersion
|RECORD=41|OwnerIndex=453|IndexInSheet=16|OwnerPartId=-1|Location.X=1527|Location.Y=1002|Color=8388608|FontID=1|IsHidden=T|Text=Manufacturer URL|Name=ComponentLink1Description
|RECORD=41|OwnerIndex=453|IndexInSheet=17|OwnerPartId=-1|Location.X=1527|Location.Y=1002|Color=8388608|FontID=1|IsHidden=T|Text=-55 degC|Name=Min Operating Temperature
|RECORD=41|OwnerIndex=453|IndexInSheet=18|OwnerPartId=-1|Location.X=1527|Location.Y=1002|Color=8388608|FontID=1|IsHidden=T|Text=Tape and Reel|Name=Packaging
|RECORD=41|OwnerIndex=453|IndexInSheet=19|OwnerPartId=-1|Location.X=1527|Location.Y=1002|Color=8388608|FontID=1|IsHidden=T|Text=No|Name=Radiation Hardening
|RECORD=41|OwnerIndex=453|IndexInSheet=20|OwnerPartId=-1|Location.X=1527|Location.Y=1002|Color=8388608|FontID=8|IsHidden=T|Text=http://industrial.panasonic.com/cdbs/www-data/pdf/RDA0000/AOA0000C86.pdf|Name=ComponentLink2URL
|RECORD=41|OwnerIndex=453|IndexInSheet=21|OwnerPartId=-1|Location.X=1527|Location.Y=1002|Color=8388608|FontID=1|IsHidden=T|Text=3216|Name=Case Code (Metric)
|RECORD=41|OwnerIndex=453|IndexInSheet=22|OwnerPartId=-1|Location.X=1527|Location.Y=1002|Color=8388608|FontID=1|IsHidden=T|Text=8|Name=Pins
|RECORD=41|OwnerIndex=453|IndexInSheet=23|OwnerPartId=-1|Location.X=1527|Location.Y=1002|Color=8388608|FontID=1|IsHidden=T|Text=1206|Name=Case Code (Imperial)
|RECORD=41|OwnerIndex=453|IndexInSheet=24|OwnerPartId=-1|Location.X=1527|Location.Y=1002|Color=8388608|FontID=1|IsHidden=T|Text=Thick Film|Name=Type (Resistor)
|RECORD=41|OwnerIndex=453|IndexInSheet=25|OwnerPartId=-1|Location.X=1527|Location.Y=1002|Color=8388608|FontID=1|IsHidden=T|Text=true|Name=RoHSCompliant
|RECORD=41|OwnerIndex=453|IndexInSheet=26|OwnerPartId=-1|Location.X=1527|Location.Y=1002|Color=8388608|FontID=1|IsHidden=T|Text=5%|Name=Tolerance
|RECORD=41|OwnerIndex=453|IndexInSheet=27|OwnerPartId=-1|Location.X=1527|Location.Y=1002|Color=8388608|FontID=1|IsHidden=T|Text=Datasheet|Name=ComponentLink2Description
|RECORD=41|OwnerIndex=453|IndexInSheet=28|OwnerPartId=-1|Location.X=1527|Location.Y=1002|Color=8388608|FontID=1|IsHidden=T|Text=2-Pin Surface Mount Device, Body 1.6 x 0.85 mm|Name=PackageDescription
|RECORD=41|OwnerIndex=453|IndexInSheet=29|OwnerPartId=-1|Location.X=1527|Location.Y=1002|Color=8388608|FontID=8|IsHidden=T|Text=http://www.panasonic.com/|Name=ComponentLink1URL
|RECORD=41|OwnerIndex=453|IndexInSheet=30|OwnerPartId=-1|Location.X=1527|Location.Y=1002|Color=8388608|FontID=1|IsHidden=T|Text=250 mW|Name=Power Rating
|RECORD=34|OwnerIndex=453|IndexInSheet=-1|OwnerPartId=-1|Location.X=1533|Location.Y=981|Color=8388608|FontID=1|Text=R26|Name=Designator|ReadOnlyState=1
|RECORD=41|OwnerIndex=453|IndexInSheet=-1|OwnerPartId=-1|Location.X=1533|Location.Y=971|Color=8388608|FontID=1|Text=4.7K|Name=Comment
|RECORD=44|OwnerIndex=453
|RECORD=45|OwnerIndex=489|IndexInSheet=-1|Description=Chip Resistor, 2-Leads, Body 1.75x0.95mm, IPC Medium Density|UseComponentLibrary=T|ModelName=RESC1608X55X30NL15T15|ModelType=PCBLIB|DatafileCount=1|ModelDatafileEntity0=RESC1608X55X30NL15T15|ModelDatafileKind0=PCBLib|IsCurrent=T|DatalinksLocked=T|DatabaseDatalinksLocked=T
|RECORD=46|OwnerIndex=490
|RECORD=48|OwnerIndex=490
|RECORD=41|OwnerIndex=492|IndexInSheet=-1|OwnerPartId=-1|Color=8388608|FontID=1|IsHidden=T|Text=2D|Name=Available Preview Images
|RECORD=45|OwnerIndex=489|IndexInSheet=-1|Description=Chip Resistor, 2-Leads, Body 1.75x0.95mm, IPC Low Density|UseComponentLibrary=T|ModelName=RESC1608X55X30ML15T15|ModelType=PCBLIB|DatafileCount=1|ModelDatafileEntity0=RESC1608X55X30ML15T15|ModelDatafileKind0=PCBLib|DatalinksLocked=T|DatabaseDatalinksLocked=T
|RECORD=46|OwnerIndex=494
|RECORD=48|OwnerIndex=494
|RECORD=41|OwnerIndex=496|IndexInSheet=-1|OwnerPartId=-1|Color=8388608|FontID=1|IsHidden=T|Text=2D|Name=Available Preview Images
|RECORD=45|OwnerIndex=489|IndexInSheet=-1|Description=Chip Resistor, 2-Leads, Body 1.75x0.95mm, IPC High Density|UseComponentLibrary=T|ModelName=RESC1608X55X30LL15T15|ModelType=PCBLIB|DatafileCount=1|ModelDatafileEntity0=RESC1608X55X30LL15T15|ModelDatafileKind0=PCBLib|DatalinksLocked=T|DatabaseDatalinksLocked=T
|RECORD=46|OwnerIndex=498
|RECORD=48|OwnerIndex=498
|RECORD=41|OwnerIndex=500|IndexInSheet=-1|OwnerPartId=-1|Color=8388608|FontID=1|IsHidden=T|Text=2D|Name=Available Preview Images
|RECORD=17|IndexInSheet=54|OwnerPartId=-1|ShowNetName=T|Location.X=180|Location.Y=670|Orientation=1|Color=128|FontID=1|Text=+5.0V
|RECORD=17|IndexInSheet=55|OwnerPartId=-1|Style=4|ShowNetName=T|Location.X=600|Location.Y=580|Orientation=3|Color=128|FontID=1|Text=GND
|RECORD=17|IndexInSheet=56|OwnerPartId=-1|ShowNetName=T|Location.X=80|Location.Y=670|Orientation=1|Color=128|FontID=1|Text=+3.3V
|RECORD=17|IndexInSheet=57|OwnerPartId=-1|Style=4|ShowNetName=T|Location.X=80|Location.Y=590|Orientation=3|Color=128|FontID=1|Text=GND
|RECORD=17|IndexInSheet=58|OwnerPartId=-1|Style=4|ShowNetName=T|Location.X=180|Location.Y=590|Orientation=3|Color=128|FontID=1|Text=GND
|RECORD=17|IndexInSheet=59|OwnerPartId=-1|ShowNetName=T|Location.X=670|Location.Y=640|Color=255|FontID=1|Text=GPS2_TP2|IsCrossSheetConnector=T
|RECORD=17|IndexInSheet=60|OwnerPartId=-1|ShowNetName=T|Location.X=670|Location.Y=630|Color=255|FontID=1|Text=GPS2_TP1|IsCrossSheetConnector=T
|RECORD=17|IndexInSheet=61|OwnerPartId=-1|ShowNetName=T|Location.X=670|Location.Y=620|Color=255|FontID=1|Text=GPS2_RX|IsCrossSheetConnector=T
|RECORD=17|IndexInSheet=62|OwnerPartId=-1|ShowNetName=T|Location.X=330|Location.Y=630|Orientation=2|Color=255|FontID=1|Text=GPS2_TX|IsCrossSheetConnector=T
|RECORD=17|IndexInSheet=63|OwnerPartId=-1|ShowNetName=T|Location.X=330|Location.Y=620|Orientation=2|Color=255|FontID=1|Text=GPS2_RST|IsCrossSheetConnector=T
|RECORD=1|LibReference=RCB-F9T|ComponentDescription=MOD, GPS|PartCount=2|DisplayModeCount=1|IndexInSheet=64|OwnerPartId=-1|Location.X=500|Location.Y=640|CurrentPartId=1|LibraryPath=*|SourceLibraryName=Modules.IntLib|TargetFileName=*|AreaColor=11599871|Color=128|PartIDLocked=F|PinsMoveable=T|DesignItemId=RCB-F9T|AllPinCount=8
|RECORD=41|OwnerIndex=512|OwnerPartId=-1|Location.X=500|Location.Y=640|Color=8388608|FontID=9|IsHidden=T|Text=RCB-F9T-1|Name=MFG PART NUM
|RECORD=41|OwnerIndex=512|IndexInSheet=1|OwnerPartId=-1|Location.X=500|Location.Y=640|Color=8388608|FontID=9|IsHidden=T|Text=UBLOCKS|Name=MFG NAME
|RECORD=41|OwnerIndex=512|IndexInSheet=2|OwnerPartId=-1|Location.X=500|Location.Y=640|Color=8388608|FontID=9|IsHidden=T|Text=MOD|Name=CATEGORY
|RECORD=41|OwnerIndex=512|IndexInSheet=3|OwnerPartId=-1|Location.X=500|Location.Y=640|Color=8388608|FontID=9|IsHidden=T|Text=9/11/13|Name=MODIFY DATE
|RECORD=41|OwnerIndex=512|IndexInSheet=4|OwnerPartId=-1|Location.X=498|Location.Y=389|Color=8388608|FontID=1|IsHidden=T|Text=GPS|Name=P1
|RECORD=41|OwnerIndex=512|IndexInSheet=5|OwnerPartId=-1|Location.X=498|Location.Y=389|Color=8388608|FontID=1|IsHidden=T|Name=P2
|RECORD=41|OwnerIndex=512|IndexInSheet=6|OwnerPartId=-1|Location.X=498|Location.Y=389|Color=8388608|FontID=1|IsHidden=T|Name=P3
|RECORD=41|OwnerIndex=512|IndexInSheet=7|OwnerPartId=-1|Location.X=498|Location.Y=389|Color=8388608|FontID=1|IsHidden=T|Name=OTHER
|RECORD=41|OwnerIndex=512|IndexInSheet=8|OwnerPartId=-1|Location.X=498|Location.Y=389|Color=8388608|FontID=1|IsHidden=T|Name=DATE
|RECORD=41|OwnerIndex=512|IndexInSheet=9|OwnerPartId=-1|Location.X=498|Location.Y=389|Color=8388608|FontID=1|IsHidden=T|Text=*|Name=SHEETPART
|RECORD=41|OwnerIndex=512|IndexInSheet=10|OwnerPartId=-1|Location.X=498|Location.Y=389|Color=8388608|FontID=1|IsHidden=T|Name=SUB
|RECORD=41|OwnerIndex=512|IndexInSheet=11|OwnerPartId=-1|Location.X=498|Location.Y=389|Color=8388608|FontID=1|IsHidden=T|Name=SIZE
|RECORD=41|OwnerIndex=512|IndexInSheet=12|OwnerPartId=-1|Location.X=498|Location.Y=389|Color=8388608|FontID=1|IsHidden=T|Text=-40C|Name=MINTEMP
|RECORD=41|OwnerIndex=512|IndexInSheet=13|OwnerPartId=-1|Location.X=498|Location.Y=389|Color=8388608|FontID=1|IsHidden=T|Text=80C|Name=MAXTEMP
|RECORD=41|OwnerIndex=512|IndexInSheet=14|OwnerPartId=-1|Location.X=498|Location.Y=379|Color=8388608|FontID=1|IsHidden=T|Text=.|Name=DATE
|RECORD=41|OwnerIndex=512|IndexInSheet=15|OwnerPartId=-1|Location.X=498|Location.Y=694|Color=8388608|FontID=1|IsHidden=T|Text=MOD BLE 4.2|Name=DESC
|RECORD=41|OwnerIndex=512|IndexInSheet=16|OwnerPartId=-1|Location.X=468|Location.Y=712|Color=8388608|FontID=1|IsHidden=T|Text=<V PART NUM>|Name=VELENTIUM PART NUM
|RECORD=41|OwnerIndex=512|IndexInSheet=17|OwnerPartId=-1|Location.X=418|Location.Y=694|Color=8388608|FontID=1|IsHidden=T|Text=Digi-Key|Name=Supplier 1|ReadOnlyState=3
|RECORD=41|OwnerIndex=512|IndexInSheet=18|OwnerPartId=-1|Location.X=418|Location.Y=694|Color=8388608|FontID=1|IsHidden=T|Text=672-RCB-F9T-ND|Name=Supplier Part Number 1|ReadOnlyState=3
|RECORD=14|OwnerIndex=512|IsNotAccesible=T|IndexInSheet=19|OwnerPartId=1|Location.X=450|Location.Y=610|Corner.X=550|Corner.Y=660|Color=128|AreaColor=11599871|IsSolid=T
|RECORD=2|OwnerIndex=512|OwnerPartId=1|FormalType=1|Electrical=4|PinConglomerate=26|PinLength=30|Location.X=450|Location.Y=650|Name=VCC_ANT|Designator=1|SwapIDPart=Ž&Ž||PinPropagationDelay=0.000000E+000
|RECORD=2|OwnerIndex=512|OwnerPartId=1|FormalType=1|Electrical=4|PinConglomerate=26|PinLength=30|Location.X=450|Location.Y=640|Name=VCC|Designator=2|SwapIDPart=Ž&Ž||PinPropagationDelay=0.000000E+000
|RECORD=2|OwnerIndex=512|OwnerPartId=1|FormalType=1|Electrical=4|PinConglomerate=26|PinLength=30|Location.X=450|Location.Y=630|Name=TXD|Designator=3|SwapIDPart=Ž&Ž||PinPropagationDelay=0.000000E+000
|RECORD=2|OwnerIndex=512|OwnerPartId=1|FormalType=1|Electrical=4|PinConglomerate=26|PinLength=30|Location.X=450|Location.Y=620|Name=RST|Designator=4|SwapIDPart=Ž&Ž||PinPropagationDelay=0.000000E+000
|RECORD=2|OwnerIndex=512|OwnerPartId=1|FormalType=1|Electrical=4|PinConglomerate=24|PinLength=30|Location.X=550|Location.Y=620|Name=RXD|Designator=5|SwapIDPart=Ž&Ž||PinPropagationDelay=0.000000E+000
|RECORD=2|OwnerIndex=512|OwnerPartId=1|FormalType=1|Electrical=4|PinConglomerate=24|PinLength=30|Location.X=550|Location.Y=630|Name=TP1|Designator=6|SwapIDPart=Ž&Ž||PinPropagationDelay=0.000000E+000
|RECORD=2|OwnerIndex=512|OwnerPartId=1|FormalType=1|Electrical=4|PinConglomerate=24|PinLength=30|Location.X=550|Location.Y=640|Name=TP2|Designator=7|SwapIDPart=Ž&Ž||PinPropagationDelay=0.000000E+000
|RECORD=2|OwnerIndex=512|OwnerPartId=1|FormalType=1|Electrical=4|PinConglomerate=24|PinLength=30|Location.X=550|Location.Y=650|Name=GND|Designator=8|SwapIDPart=Ž&Ž||PinPropagationDelay=0.000000E+000
|RECORD=34|OwnerIndex=512|IndexInSheet=-1|OwnerPartId=-1|Location.X=450|Location.Y=660|Color=8388608|FontID=1|Text=U15|Name=Designator|ReadOnlyState=1
|RECORD=41|OwnerIndex=512|IndexInSheet=-1|OwnerPartId=-1|Location.X=450|Location.Y=598|Color=8388608|FontID=1|Text=RCB-F9T-1|Name=Comment
|RECORD=44|OwnerIndex=512
|RECORD=45|OwnerIndex=551|IndexInSheet=-1|ModelName=GNSS|ModelType=PCBLIB|DatafileCount=1|ModelDatafileEntity0=GNSS|ModelDatafileKind0=PCBLib|IsCurrent=T|IntegratedModel=T|DatabaseModel=T
|RECORD=46|OwnerIndex=552
|RECORD=48|OwnerIndex=552
|RECORD=1|LibReference=CAP|ComponentDescription=C0603X104K5RACAUTO|PartCount=2|DisplayModeCount=2|IndexInSheet=65|OwnerPartId=-1|Location.X=120|Location.Y=610|Orientation=1|CurrentPartId=1|SourceLibraryName=Altium Content Vault|TargetFileName=*|AreaColor=11599871|Color=128|PartIDLocked=F|DesignItemId=CMP-2006-00003-1|AllPinCount=2
|RECORD=2|OwnerIndex=555|OwnerPartId=1|OwnerPartDisplayMode=1|FormalType=1|Electrical=4|PinConglomerate=35|PinLength=10|Location.X=130|Location.Y=610|Name=1|Designator=1|PinPropagationDelay=0.000000E+000
|RECORD=2|OwnerIndex=555|OwnerPartId=1|OwnerPartDisplayMode=1|FormalType=1|Electrical=4|PinConglomerate=33|PinLength=10|Location.X=130|Location.Y=620|Name=2|Designator=2|PinPropagationDelay=0.000000E+000
|RECORD=13|OwnerIndex=555|IsNotAccesible=T|IndexInSheet=2|OwnerPartId=1|OwnerPartDisplayMode=1|Location.X=138|Location.Y=610|Corner.X=122|Corner.Y=610|LineWidth=1|Color=16711680
|RECORD=13|OwnerIndex=555|IsNotAccesible=T|IndexInSheet=3|OwnerPartId=1|OwnerPartDisplayMode=1|Location.X=130|Location.Y=614|Corner.X=130|Corner.Y=620|LineWidth=1|Color=16711680
|RECORD=12|OwnerIndex=555|IsNotAccesible=T|IndexInSheet=4|OwnerPartId=1|OwnerPartDisplayMode=1|Location.X=130|Location.Y=630|Radius=16|LineWidth=1|StartAngle=241.000|EndAngle=270.000|Color=16711680
|RECORD=12|OwnerIndex=555|IsNotAccesible=T|IndexInSheet=5|OwnerPartId=1|OwnerPartDisplayMode=1|Location.X=130|Location.Y=630|Radius=16|LineWidth=1|StartAngle=270.000|EndAngle=299.000|Color=16711680
|RECORD=2|OwnerIndex=555|OwnerPartId=1|FormalType=1|Electrical=4|PinConglomerate=35|PinLength=10|Location.X=130|Location.Y=610|Name=1|Designator=1|PinPropagationDelay=0.000000E+000
|RECORD=2|OwnerIndex=555|OwnerPartId=1|FormalType=1|Electrical=4|PinConglomerate=33|PinLength=10|Location.X=130|Location.Y=620|Name=2|Designator=2|PinPropagationDelay=0.000000E+000
|RECORD=13|OwnerIndex=555|IsNotAccesible=T|IndexInSheet=8|OwnerPartId=1|Location.X=122|Location.Y=617|Corner.X=138|Corner.Y=617|LineWidth=1|Color=16711680
|RECORD=13|OwnerIndex=555|IsNotAccesible=T|IndexInSheet=9|OwnerPartId=1|Location.X=138|Location.Y=613|Corner.X=122|Corner.Y=613|LineWidth=1|Color=16711680
|RECORD=6|OwnerIndex=555|IsNotAccesible=T|IndexInSheet=10|OwnerPartId=1|LineWidth=1|Color=16711680|LocationCount=2|X1=130|Y1=610|X2=130|Y2=613
|RECORD=6|OwnerIndex=555|IsNotAccesible=T|IndexInSheet=11|OwnerPartId=1|LineWidth=1|Color=16711680|LocationCount=2|X1=130|Y1=620|X2=130|Y2=617
|RECORD=41|OwnerIndex=555|IndexInSheet=12|OwnerPartId=-1|Location.X=121|Location.Y=632|Color=8388608|FontID=1|IsHidden=T|Text=Kemet|Name=Manufacturer
|RECORD=41|OwnerIndex=555|IndexInSheet=13|OwnerPartId=-1|Location.X=121|Location.Y=632|Color=8388608|FontID=1|IsHidden=T|Text=C0603X104K5RACAUTO|Name=Part Number
|RECORD=34|OwnerIndex=555|IndexInSheet=-1|OwnerPartId=-1|Location.X=139|Location.Y=611|Color=8388608|FontID=1|Text=C36|Name=Designator|ReadOnlyState=1
|RECORD=41|OwnerIndex=555|IndexInSheet=-1|OwnerPartId=-1|Location.X=139|Location.Y=601|Color=8388608|FontID=1|Text=0.1uF|Name=Comment
|RECORD=44|OwnerIndex=555
|RECORD=45|OwnerIndex=576|IndexInSheet=-1|Description=Chip Capacitor, 2-Leads, Body 1.60x0.80mm, IPC Low Density|UseComponentLibrary=T|ModelName=CAPC1608X87X45ML20T05|ModelType=PCBLIB|DatafileCount=1|ModelDatafileEntity0=CAPC1608X87X45ML20T05|ModelDatafileKind0=PCBLib|IsCurrent=T|DatalinksLocked=T|DatabaseDatalinksLocked=T
|RECORD=46|OwnerIndex=577
|RECORD=48|OwnerIndex=577
|RECORD=41|OwnerIndex=579|IndexInSheet=-1|OwnerPartId=-1|Color=8388608|FontID=1|Text=2D|Name=Available Preview Images
|RECORD=45|OwnerIndex=576|IndexInSheet=-1|Description=Chip Capacitor, 2-Leads, Body 1.60x0.80mm, IPC High Density|UseComponentLibrary=T|ModelName=CAPC1608X87X45LL20T05|ModelType=PCBLIB|DatafileCount=1|ModelDatafileEntity0=CAPC1608X87X45LL20T05|ModelDatafileKind0=PCBLib|DatalinksLocked=T|DatabaseDatalinksLocked=T
|RECORD=46|OwnerIndex=581
|RECORD=48|OwnerIndex=581
|RECORD=41|OwnerIndex=583|IndexInSheet=-1|OwnerPartId=-1|Color=8388608|FontID=1|Text=2D|Name=Available Preview Images
|RECORD=45|OwnerIndex=576|IndexInSheet=-1|Description=Chip Capacitor, 2-Leads, Body 1.60x0.80mm, IPC Medium Density|UseComponentLibrary=T|ModelName=CAPC1608X87X45NL20T05|ModelType=PCBLIB|DatafileCount=1|ModelDatafileEntity0=CAPC1608X87X45NL20T05|ModelDatafileKind0=PCBLib|DatalinksLocked=T|DatabaseDatalinksLocked=T
|RECORD=46|OwnerIndex=585
|RECORD=48|OwnerIndex=585
|RECORD=41|OwnerIndex=587|IndexInSheet=-1|OwnerPartId=-1|Color=8388608|FontID=1|Text=2D|Name=Available Preview Images
|RECORD=1|LibReference=CAP|ComponentDescription=C0603X104K5RACAUTO|PartCount=2|DisplayModeCount=2|IndexInSheet=66|OwnerPartId=-1|Location.X=220|Location.Y=610|Orientation=1|CurrentPartId=1|SourceLibraryName=Altium Content Vault|TargetFileName=*|AreaColor=11599871|Color=128|PartIDLocked=F|DesignItemId=CMP-2006-00003-1|AllPinCount=2
|RECORD=2|OwnerIndex=589|OwnerPartId=1|OwnerPartDisplayMode=1|FormalType=1|Electrical=4|PinConglomerate=35|PinLength=10|Location.X=230|Location.Y=610|Name=1|Designator=1|PinPropagationDelay=0.000000E+000
|RECORD=2|OwnerIndex=589|OwnerPartId=1|OwnerPartDisplayMode=1|FormalType=1|Electrical=4|PinConglomerate=33|PinLength=10|Location.X=230|Location.Y=620|Name=2|Designator=2|PinPropagationDelay=0.000000E+000
|RECORD=13|OwnerIndex=589|IsNotAccesible=T|IndexInSheet=2|OwnerPartId=1|OwnerPartDisplayMode=1|Location.X=238|Location.Y=610|Corner.X=222|Corner.Y=610|LineWidth=1|Color=16711680
|RECORD=13|OwnerIndex=589|IsNotAccesible=T|IndexInSheet=3|OwnerPartId=1|OwnerPartDisplayMode=1|Location.X=230|Location.Y=614|Corner.X=230|Corner.Y=620|LineWidth=1|Color=16711680
|RECORD=12|OwnerIndex=589|IsNotAccesible=T|IndexInSheet=4|OwnerPartId=1|OwnerPartDisplayMode=1|Location.X=230|Location.Y=630|Radius=16|LineWidth=1|StartAngle=241.000|EndAngle=270.000|Color=16711680
|RECORD=12|OwnerIndex=589|IsNotAccesible=T|IndexInSheet=5|OwnerPartId=1|OwnerPartDisplayMode=1|Location.X=230|Location.Y=630|Radius=16|LineWidth=1|StartAngle=270.000|EndAngle=299.000|Color=16711680
|RECORD=2|OwnerIndex=589|OwnerPartId=1|FormalType=1|Electrical=4|PinConglomerate=35|PinLength=10|Location.X=230|Location.Y=610|Name=1|Designator=1|PinPropagationDelay=0.000000E+000
|RECORD=2|OwnerIndex=589|OwnerPartId=1|FormalType=1|Electrical=4|PinConglomerate=33|PinLength=10|Location.X=230|Location.Y=620|Name=2|Designator=2|PinPropagationDelay=0.000000E+000
|RECORD=13|OwnerIndex=589|IsNotAccesible=T|IndexInSheet=8|OwnerPartId=1|Location.X=222|Location.Y=617|Corner.X=238|Corner.Y=617|LineWidth=1|Color=16711680
|RECORD=13|OwnerIndex=589|IsNotAccesible=T|IndexInSheet=9|OwnerPartId=1|Location.X=238|Location.Y=613|Corner.X=222|Corner.Y=613|LineWidth=1|Color=16711680
|RECORD=6|OwnerIndex=589|IsNotAccesible=T|IndexInSheet=10|OwnerPartId=1|LineWidth=1|Color=16711680|LocationCount=2|X1=230|Y1=610|X2=230|Y2=613
|RECORD=6|OwnerIndex=589|IsNotAccesible=T|IndexInSheet=11|OwnerPartId=1|LineWidth=1|Color=16711680|LocationCount=2|X1=230|Y1=620|X2=230|Y2=617
|RECORD=41|OwnerIndex=589|IndexInSheet=12|OwnerPartId=-1|Location.X=221|Location.Y=632|Color=8388608|FontID=1|IsHidden=T|Text=Kemet|Name=Manufacturer
|RECORD=41|OwnerIndex=589|IndexInSheet=13|OwnerPartId=-1|Location.X=221|Location.Y=632|Color=8388608|FontID=1|IsHidden=T|Text=C0603X104K5RACAUTO|Name=Part Number
|RECORD=34|OwnerIndex=589|IndexInSheet=-1|OwnerPartId=-1|Location.X=239|Location.Y=611|Color=8388608|FontID=1|Text=C37|Name=Designator|ReadOnlyState=1
|RECORD=41|OwnerIndex=589|IndexInSheet=-1|OwnerPartId=-1|Location.X=239|Location.Y=601|Color=8388608|FontID=1|Text=0.1uF|Name=Comment
|RECORD=44|OwnerIndex=589
|RECORD=45|OwnerIndex=610|IndexInSheet=-1|Description=Chip Capacitor, 2-Leads, Body 1.60x0.80mm, IPC Low Density|UseComponentLibrary=T|ModelName=CAPC1608X87X45ML20T05|ModelType=PCBLIB|DatafileCount=1|ModelDatafileEntity0=CAPC1608X87X45ML20T05|ModelDatafileKind0=PCBLib|IsCurrent=T|DatalinksLocked=T|DatabaseDatalinksLocked=T
|RECORD=46|OwnerIndex=611
|RECORD=48|OwnerIndex=611
|RECORD=41|OwnerIndex=613|IndexInSheet=-1|OwnerPartId=-1|Color=8388608|FontID=1|Text=2D|Name=Available Preview Images
|RECORD=45|OwnerIndex=610|IndexInSheet=-1|Description=Chip Capacitor, 2-Leads, Body 1.60x0.80mm, IPC High Density|UseComponentLibrary=T|ModelName=CAPC1608X87X45LL20T05|ModelType=PCBLIB|DatafileCount=1|ModelDatafileEntity0=CAPC1608X87X45LL20T05|ModelDatafileKind0=PCBLib|DatalinksLocked=T|DatabaseDatalinksLocked=T
|RECORD=46|OwnerIndex=615
|RECORD=48|OwnerIndex=615
|RECORD=41|OwnerIndex=617|IndexInSheet=-1|OwnerPartId=-1|Color=8388608|FontID=1|Text=2D|Name=Available Preview Images
|RECORD=45|OwnerIndex=610|IndexInSheet=-1|Description=Chip Capacitor, 2-Leads, Body 1.60x0.80mm, IPC Medium Density|UseComponentLibrary=T|ModelName=CAPC1608X87X45NL20T05|ModelType=PCBLIB|DatafileCount=1|ModelDatafileEntity0=CAPC1608X87X45NL20T05|ModelDatafileKind0=PCBLib|DatalinksLocked=T|DatabaseDatalinksLocked=T
|RECORD=46|OwnerIndex=619
|RECORD=48|OwnerIndex=619
|RECORD=41|OwnerIndex=621|IndexInSheet=-1|OwnerPartId=-1|Color=8388608|FontID=1|Text=2D|Name=Available Preview Images
|RECORD=1|LibReference=b4654b650e69147ec39a6b967a45e02|ComponentDescription=None|PartCount=2|DisplayModeCount=1|IndexInSheet=67|OwnerPartId=-1|Location.X=190|Location.Y=840|CurrentPartId=1|LibraryPath=*|SourceLibraryName=Altium Content Vault|TargetFileName=*|AreaColor=11599871|Color=128|PartIDLocked=T|DesignItemId=CMP-14477-000079-2|AllPinCount=2
|RECORD=2|OwnerIndex=623|OwnerPartId=1|Electrical=4|PinConglomerate=49|PinLength=7|Location.X=190|Location.Y=833|Name=1|Designator=1|PinPropagationDelay=0.000000E+000
|RECORD=2|OwnerIndex=623|OwnerPartId=1|Electrical=4|PinConglomerate=51|PinLength=6|Location.X=190|Location.Y=826|Name=2|Designator=2|PinPropagationDelay=0.000000E+000
|RECORD=13|OwnerIndex=623|IsNotAccesible=T|IndexInSheet=2|OwnerPartId=1|Location.X=200|Location.Y=833|Corner.X=180|Corner.Y=833|LineWidth=1|Color=16711680
|RECORD=13|OwnerIndex=623|IsNotAccesible=T|IndexInSheet=3|OwnerPartId=1|Location.X=200|Location.Y=827|Corner.X=180|Corner.Y=827|LineWidth=1|Color=16711680
|RECORD=13|OwnerIndex=623|IsNotAccesible=T|IndexInSheet=4|OwnerPartId=1|Location.X=190|Location.Y=833|Corner.X=190|Corner.Y=836|LineWidth=1|Color=16711680
|RECORD=13|OwnerIndex=623|IsNotAccesible=T|IndexInSheet=5|OwnerPartId=1|Location.X=190|Location.Y=826|Corner.X=190|Corner.Y=825|LineWidth=1|Color=16711680
|RECORD=41|OwnerIndex=623|IndexInSheet=6|OwnerPartId=-1|Location.X=179|Location.Y=842|Color=8388608|FontID=1|IsHidden=T|Text=Tape and Reel|Name=Packaging
|RECORD=41|OwnerIndex=623|IndexInSheet=7|OwnerPartId=-1|Location.X=179|Location.Y=842|Color=8388608|FontID=1|IsHidden=T|Text=10uF|Name=Capacitance
|RECORD=41|OwnerIndex=623|IndexInSheet=8|OwnerPartId=-1|Location.X=179|Location.Y=842|Color=8388608|FontID=1|IsHidden=T|Text=25V|Name=Voltage Rating (DC)
|RECORD=41|OwnerIndex=623|IndexInSheet=9|OwnerPartId=-1|Location.X=179|Location.Y=842|Color=8388608|FontID=1|IsHidden=T|Text=0.053inch|Name=Thickness
|RECORD=41|OwnerIndex=623|IndexInSheet=10|OwnerPartId=-1|Location.X=179|Location.Y=842|Color=8388608|FontID=1|IsHidden=T|Text=Ceramic|Name=Resistor Type
|RECORD=41|OwnerIndex=623|IndexInSheet=11|OwnerPartId=-1|Location.X=179|Location.Y=842|Color=8388608|FontID=1|IsHidden=T|Text=Yes|Name=RoHS Compliant
|RECORD=41|OwnerIndex=623|IndexInSheet=12|OwnerPartId=-1|Location.X=179|Location.Y=842|Color=8388608|FontID=1|IsHidden=T|Text=Lead Free|Name=Lead Free
|RECORD=41|OwnerIndex=623|IndexInSheet=13|OwnerPartId=-1|Location.X=179|Location.Y=842|Color=8388608|FontID=1|IsHidden=T|Text=No SVHC|Name=REACH SVHC
|RECORD=41|OwnerIndex=623|IndexInSheet=14|OwnerPartId=-1|Location.X=179|Location.Y=842|Color=8388608|FontID=1|IsHidden=T|Text=2|Name=Number of Pins
|RECORD=41|OwnerIndex=623|IndexInSheet=15|OwnerPartId=-1|Location.X=179|Location.Y=842|Color=8388608|FontID=1|IsHidden=T|Text=1|Name=Package Quantity
|RECORD=41|OwnerIndex=623|IndexInSheet=16|OwnerPartId=-1|Location.X=179|Location.Y=842|Color=8388608|FontID=1|IsHidden=T|Text=Surface Mount|Name=Mount
|RECORD=41|OwnerIndex=623|IndexInSheet=17|OwnerPartId=-1|Location.X=179|Location.Y=842|Color=8388608|FontID=1|IsHidden=T|Text=SMD/SMT|Name=Termination
|RECORD=41|OwnerIndex=623|IndexInSheet=18|OwnerPartId=-1|Location.X=179|Location.Y=842|Color=8388608|FontID=1|IsHidden=T|Text=0.049inch|Name=Width
|RECORD=41|OwnerIndex=623|IndexInSheet=19|OwnerPartId=-1|Location.X=179|Location.Y=842|Color=8388608|FontID=1|IsHidden=T|Text=85°C|Name=Max Operating Temperature
|RECORD=41|OwnerIndex=623|IndexInSheet=20|OwnerPartId=-1|Location.X=179|Location.Y=842|Color=8388608|FontID=1|IsHidden=T|Text=0.079inch|Name=Length
|RECORD=41|OwnerIndex=623|IndexInSheet=21|OwnerPartId=-1|Location.X=179|Location.Y=842|Color=8388608|FontID=1|IsHidden=T|Text=0805|Name=Case/Package
|RECORD=41|OwnerIndex=623|IndexInSheet=22|OwnerPartId=-1|Location.X=179|Location.Y=842|Color=8388608|FontID=1|IsHidden=T|Text=25V|Name=Voltage Rating
|RECORD=41|OwnerIndex=623|IndexInSheet=23|OwnerPartId=-1|Location.X=179|Location.Y=842|Color=8388608|FontID=1|IsHidden=T|Text=-55°C|Name=Min Operating Temperature
|RECORD=41|OwnerIndex=623|IndexInSheet=24|OwnerPartId=-1|Location.X=179|Location.Y=842|Color=8388608|FontID=1|IsHidden=T|Text=10%|Name=Tolerance
|RECORD=41|OwnerIndex=623|IndexInSheet=25|OwnerPartId=-1|Location.X=179|Location.Y=842|Color=8388608|FontID=1|IsHidden=T|Text=X7R|Name=Dielectric
|RECORD=41|OwnerIndex=623|IndexInSheet=26|OwnerPartId=-1|Location.X=179|Location.Y=842|Color=8388608|FontID=1|IsHidden=T|Text=2012|Name=Case Code (Metric)
|RECORD=41|OwnerIndex=623|IndexInSheet=27|OwnerPartId=-1|Location.X=179|Location.Y=842|Color=8388608|FontID=1|IsHidden=T|Text=0805|Name=Case Code (Imperial)
|RECORD=41|OwnerIndex=623|IndexInSheet=28|OwnerPartId=-1|Location.X=179|Location.Y=842|Color=8388608|FontID=1|IsHidden=T|Text=1.25mm|Name=Height
|RECORD=41|OwnerIndex=623|IndexInSheet=29|OwnerPartId=-1|Location.X=179|Location.Y=842|Color=8388608|FontID=1|IsHidden=T|Text=16V|Name=Voltage
|RECORD=41|OwnerIndex=623|IndexInSheet=30|OwnerPartId=-1|Location.X=179|Location.Y=842|Color=8388608|FontID=1|IsHidden=T|Text=M|Name=Series
|RECORD=34|OwnerIndex=623|IndexInSheet=-1|OwnerPartId=-1|Location.X=201|Location.Y=827|Color=8388608|FontID=1|Text=C58|Name=Designator|ReadOnlyState=1
|RECORD=41|OwnerIndex=623|IndexInSheet=-1|OwnerPartId=1|Location.X=201|Location.Y=817|Color=8388608|FontID=1|Text=10uF|Name=Comment
|RECORD=44|OwnerIndex=623
|RECORD=45|OwnerIndex=659|IndexInSheet=-1|UseComponentLibrary=T|ModelName=FP-MK212BG-MFG|ModelType=PCBLIB|DatafileCount=1|ModelDatafileEntity0=FP-MK212BG-MFG|ModelDatafileKind0=PCBLib|IsCurrent=T|DatalinksLocked=T|DatabaseDatalinksLocked=T
|RECORD=46|OwnerIndex=660
|RECORD=48|OwnerIndex=660
|RECORD=45|OwnerIndex=659|IndexInSheet=-1|UseComponentLibrary=T|ModelName=FP-MK212BG-IPC_C|ModelType=PCBLIB|DatafileCount=1|ModelDatafileEntity0=FP-MK212BG-IPC_C|ModelDatafileKind0=PCBLib|DatalinksLocked=T|DatabaseDatalinksLocked=T
|RECORD=46|OwnerIndex=663
|RECORD=48|OwnerIndex=663
|RECORD=45|OwnerIndex=659|IndexInSheet=-1|UseComponentLibrary=T|ModelName=FP-MK212BG-IPC_B|ModelType=PCBLIB|DatafileCount=1|ModelDatafileEntity0=FP-MK212BG-IPC_B|ModelDatafileKind0=PCBLib|DatalinksLocked=T|DatabaseDatalinksLocked=T
|RECORD=46|OwnerIndex=666
|RECORD=48|OwnerIndex=666
|RECORD=45|OwnerIndex=659|IndexInSheet=-1|UseComponentLibrary=T|ModelName=FP-MK212BG-IPC_A|ModelType=PCBLIB|DatafileCount=1|ModelDatafileEntity0=FP-MK212BG-IPC_A|ModelDatafileKind0=PCBLib|DatalinksLocked=T|DatabaseDatalinksLocked=T
|RECORD=46|OwnerIndex=669
|RECORD=48|OwnerIndex=669
|RECORD=45|OwnerIndex=659|IndexInSheet=-1|UseComponentLibrary=T|ModelName=TMK212BBJ106_G-T|ModelType=SIM|IsCurrent=T|DatalinksLocked=T|DatabaseDatalinksLocked=T
|RECORD=46|OwnerIndex=672
|RECORD=48|OwnerIndex=672
|RECORD=41|OwnerIndex=674|IndexInSheet=-1|OwnerPartId=-1|Color=8388608|FontID=1|IsHidden=T|Text=General|Name=Kind
|RECORD=41|OwnerIndex=674|IndexInSheet=-1|OwnerPartId=-1|Color=8388608|FontID=1|IsHidden=T|Text=Spice Subcircuit|Name=SubKind
|RECORD=41|OwnerIndex=674|IndexInSheet=-1|OwnerPartId=-1|Color=8388608|FontID=1|IsHidden=T|Name=Spice Prefix
|RECORD=41|OwnerIndex=674|IndexInSheet=-1|OwnerPartId=-1|Color=8388608|FontID=1|IsHidden=T|Name=Excluded Parts
|RECORD=41|OwnerIndex=674|IndexInSheet=-1|OwnerPartId=-1|Color=8388608|FontID=1|IsHidden=T|Name=Netlist
|RECORD=1|LibReference=b4654b650e69147ec39a6b967a45e02|ComponentDescription=None|PartCount=2|DisplayModeCount=1|IndexInSheet=68|OwnerPartId=-1|Location.X=290|Location.Y=840|CurrentPartId=1|LibraryPath=*|SourceLibraryName=Altium Content Vault|TargetFileName=*|AreaColor=11599871|Color=128|PartIDLocked=T|DesignItemId=CMP-14477-000079-2|AllPinCount=2
|RECORD=2|OwnerIndex=680|OwnerPartId=1|Electrical=4|PinConglomerate=49|PinLength=7|Location.X=290|Location.Y=833|Name=1|Designator=1|PinPropagationDelay=0.000000E+000
|RECORD=2|OwnerIndex=680|OwnerPartId=1|Electrical=4|PinConglomerate=51|PinLength=6|Location.X=290|Location.Y=826|Name=2|Designator=2|PinPropagationDelay=0.000000E+000
|RECORD=13|OwnerIndex=680|IsNotAccesible=T|IndexInSheet=2|OwnerPartId=1|Location.X=300|Location.Y=833|Corner.X=280|Corner.Y=833|LineWidth=1|Color=16711680
|RECORD=13|OwnerIndex=680|IsNotAccesible=T|IndexInSheet=3|OwnerPartId=1|Location.X=300|Location.Y=827|Corner.X=280|Corner.Y=827|LineWidth=1|Color=16711680
|RECORD=13|OwnerIndex=680|IsNotAccesible=T|IndexInSheet=4|OwnerPartId=1|Location.X=290|Location.Y=833|Corner.X=290|Corner.Y=836|LineWidth=1|Color=16711680
|RECORD=13|OwnerIndex=680|IsNotAccesible=T|IndexInSheet=5|OwnerPartId=1|Location.X=290|Location.Y=826|Corner.X=290|Corner.Y=825|LineWidth=1|Color=16711680
|RECORD=41|OwnerIndex=680|IndexInSheet=6|OwnerPartId=-1|Location.X=279|Location.Y=842|Color=8388608|FontID=1|IsHidden=T|Text=Tape and Reel|Name=Packaging
|RECORD=41|OwnerIndex=680|IndexInSheet=7|OwnerPartId=-1|Location.X=279|Location.Y=842|Color=8388608|FontID=1|IsHidden=T|Text=10uF|Name=Capacitance
|RECORD=41|OwnerIndex=680|IndexInSheet=8|OwnerPartId=-1|Location.X=279|Location.Y=842|Color=8388608|FontID=1|IsHidden=T|Text=25V|Name=Voltage Rating (DC)
|RECORD=41|OwnerIndex=680|IndexInSheet=9|OwnerPartId=-1|Location.X=279|Location.Y=842|Color=8388608|FontID=1|IsHidden=T|Text=0.053inch|Name=Thickness
|RECORD=41|OwnerIndex=680|IndexInSheet=10|OwnerPartId=-1|Location.X=279|Location.Y=842|Color=8388608|FontID=1|IsHidden=T|Text=Ceramic|Name=Resistor Type
|RECORD=41|OwnerIndex=680|IndexInSheet=11|OwnerPartId=-1|Location.X=279|Location.Y=842|Color=8388608|FontID=1|IsHidden=T|Text=Yes|Name=RoHS Compliant
|RECORD=41|OwnerIndex=680|IndexInSheet=12|OwnerPartId=-1|Location.X=279|Location.Y=842|Color=8388608|FontID=1|IsHidden=T|Text=Lead Free|Name=Lead Free
|RECORD=41|OwnerIndex=680|IndexInSheet=13|OwnerPartId=-1|Location.X=279|Location.Y=842|Color=8388608|FontID=1|IsHidden=T|Text=No SVHC|Name=REACH SVHC
|RECORD=41|OwnerIndex=680|IndexInSheet=14|OwnerPartId=-1|Location.X=279|Location.Y=842|Color=8388608|FontID=1|IsHidden=T|Text=2|Name=Number of Pins
|RECORD=41|OwnerIndex=680|IndexInSheet=15|OwnerPartId=-1|Location.X=279|Location.Y=842|Color=8388608|FontID=1|IsHidden=T|Text=1|Name=Package Quantity
|RECORD=41|OwnerIndex=680|IndexInSheet=16|OwnerPartId=-1|Location.X=279|Location.Y=842|Color=8388608|FontID=1|IsHidden=T|Text=Surface Mount|Name=Mount
|RECORD=41|OwnerIndex=680|IndexInSheet=17|OwnerPartId=-1|Location.X=279|Location.Y=842|Color=8388608|FontID=1|IsHidden=T|Text=SMD/SMT|Name=Termination
|RECORD=41|OwnerIndex=680|IndexInSheet=18|OwnerPartId=-1|Location.X=279|Location.Y=842|Color=8388608|FontID=1|IsHidden=T|Text=0.049inch|Name=Width
|RECORD=41|OwnerIndex=680|IndexInSheet=19|OwnerPartId=-1|Location.X=279|Location.Y=842|Color=8388608|FontID=1|IsHidden=T|Text=85°C|Name=Max Operating Temperature
|RECORD=41|OwnerIndex=680|IndexInSheet=20|OwnerPartId=-1|Location.X=279|Location.Y=842|Color=8388608|FontID=1|IsHidden=T|Text=0.079inch|Name=Length
|RECORD=41|OwnerIndex=680|IndexInSheet=21|OwnerPartId=-1|Location.X=279|Location.Y=842|Color=8388608|FontID=1|IsHidden=T|Text=0805|Name=Case/Package
|RECORD=41|OwnerIndex=680|IndexInSheet=22|OwnerPartId=-1|Location.X=279|Location.Y=842|Color=8388608|FontID=1|IsHidden=T|Text=25V|Name=Voltage Rating
|RECORD=41|OwnerIndex=680|IndexInSheet=23|OwnerPartId=-1|Location.X=279|Location.Y=842|Color=8388608|FontID=1|IsHidden=T|Text=-55°C|Name=Min Operating Temperature
|RECORD=41|OwnerIndex=680|IndexInSheet=24|OwnerPartId=-1|Location.X=279|Location.Y=842|Color=8388608|FontID=1|IsHidden=T|Text=10%|Name=Tolerance
|RECORD=41|OwnerIndex=680|IndexInSheet=25|OwnerPartId=-1|Location.X=279|Location.Y=842|Color=8388608|FontID=1|IsHidden=T|Text=X7R|Name=Dielectric
|RECORD=41|OwnerIndex=680|IndexInSheet=26|OwnerPartId=-1|Location.X=279|Location.Y=842|Color=8388608|FontID=1|IsHidden=T|Text=2012|Name=Case Code (Metric)
|RECORD=41|OwnerIndex=680|IndexInSheet=27|OwnerPartId=-1|Location.X=279|Location.Y=842|Color=8388608|FontID=1|IsHidden=T|Text=0805|Name=Case Code (Imperial)
|RECORD=41|OwnerIndex=680|IndexInSheet=28|OwnerPartId=-1|Location.X=279|Location.Y=842|Color=8388608|FontID=1|IsHidden=T|Text=1.25mm|Name=Height
|RECORD=41|OwnerIndex=680|IndexInSheet=29|OwnerPartId=-1|Location.X=279|Location.Y=842|Color=8388608|FontID=1|IsHidden=T|Text=16V|Name=Voltage
|RECORD=41|OwnerIndex=680|IndexInSheet=30|OwnerPartId=-1|Location.X=279|Location.Y=842|Color=8388608|FontID=1|IsHidden=T|Text=M|Name=Series
|RECORD=34|OwnerIndex=680|IndexInSheet=-1|OwnerPartId=-1|Location.X=301|Location.Y=827|Color=8388608|FontID=1|Text=C60|Name=Designator|ReadOnlyState=1
|RECORD=41|OwnerIndex=680|IndexInSheet=-1|OwnerPartId=1|Location.X=301|Location.Y=817|Color=8388608|FontID=1|Text=10uF|Name=Comment
|RECORD=44|OwnerIndex=680
|RECORD=45|OwnerIndex=716|IndexInSheet=-1|UseComponentLibrary=T|ModelName=FP-MK212BG-MFG|ModelType=PCBLIB|DatafileCount=1|ModelDatafileEntity0=FP-MK212BG-MFG|ModelDatafileKind0=PCBLib|IsCurrent=T|DatalinksLocked=T|DatabaseDatalinksLocked=T
|RECORD=46|OwnerIndex=717
|RECORD=48|OwnerIndex=717
|RECORD=45|OwnerIndex=716|IndexInSheet=-1|UseComponentLibrary=T|ModelName=FP-MK212BG-IPC_C|ModelType=PCBLIB|DatafileCount=1|ModelDatafileEntity0=FP-MK212BG-IPC_C|ModelDatafileKind0=PCBLib|DatalinksLocked=T|DatabaseDatalinksLocked=T
|RECORD=46|OwnerIndex=720
|RECORD=48|OwnerIndex=720
|RECORD=45|OwnerIndex=716|IndexInSheet=-1|UseComponentLibrary=T|ModelName=FP-MK212BG-IPC_B|ModelType=PCBLIB|DatafileCount=1|ModelDatafileEntity0=FP-MK212BG-IPC_B|ModelDatafileKind0=PCBLib|DatalinksLocked=T|DatabaseDatalinksLocked=T
|RECORD=46|OwnerIndex=723
|RECORD=48|OwnerIndex=723
|RECORD=45|OwnerIndex=716|IndexInSheet=-1|UseComponentLibrary=T|ModelName=FP-MK212BG-IPC_A|ModelType=PCBLIB|DatafileCount=1|ModelDatafileEntity0=FP-MK212BG-IPC_A|ModelDatafileKind0=PCBLib|DatalinksLocked=T|DatabaseDatalinksLocked=T
|RECORD=46|OwnerIndex=726
|RECORD=48|OwnerIndex=726
|RECORD=45|OwnerIndex=716|IndexInSheet=-1|UseComponentLibrary=T|ModelName=TMK212BBJ106_G-T|ModelType=SIM|IsCurrent=T|DatalinksLocked=T|DatabaseDatalinksLocked=T
|RECORD=46|OwnerIndex=729
|RECORD=48|OwnerIndex=729
|RECORD=41|OwnerIndex=731|IndexInSheet=-1|OwnerPartId=-1|Color=8388608|FontID=1|IsHidden=T|Text=General|Name=Kind
|RECORD=41|OwnerIndex=731|IndexInSheet=-1|OwnerPartId=-1|Color=8388608|FontID=1|IsHidden=T|Text=Spice Subcircuit|Name=SubKind
|RECORD=41|OwnerIndex=731|IndexInSheet=-1|OwnerPartId=-1|Color=8388608|FontID=1|IsHidden=T|Name=Spice Prefix
|RECORD=41|OwnerIndex=731|IndexInSheet=-1|OwnerPartId=-1|Color=8388608|FontID=1|IsHidden=T|Name=Excluded Parts
|RECORD=41|OwnerIndex=731|IndexInSheet=-1|OwnerPartId=-1|Color=8388608|FontID=1|IsHidden=T|Name=Netlist
|RECORD=1|LibReference=b4654b650e69147ec39a6b967a45e02|ComponentDescription=None|PartCount=2|DisplayModeCount=1|IndexInSheet=69|OwnerPartId=-1|Location.X=80|Location.Y=630|CurrentPartId=1|LibraryPath=*|SourceLibraryName=Altium Content Vault|TargetFileName=*|AreaColor=11599871|Color=128|PartIDLocked=T|DesignItemId=CMP-14477-000079-2|AllPinCount=2
|RECORD=2|OwnerIndex=737|OwnerPartId=1|Electrical=4|PinConglomerate=49|PinLength=7|Location.X=80|Location.Y=623|Name=1|Designator=1|PinPropagationDelay=0.000000E+000
|RECORD=2|OwnerIndex=737|OwnerPartId=1|Electrical=4|PinConglomerate=51|PinLength=6|Location.X=80|Location.Y=616|Name=2|Designator=2|PinPropagationDelay=0.000000E+000
|RECORD=13|OwnerIndex=737|IsNotAccesible=T|IndexInSheet=2|OwnerPartId=1|Location.X=90|Location.Y=623|Corner.X=70|Corner.Y=623|LineWidth=1|Color=16711680
|RECORD=13|OwnerIndex=737|IsNotAccesible=T|IndexInSheet=3|OwnerPartId=1|Location.X=90|Location.Y=617|Corner.X=70|Corner.Y=617|LineWidth=1|Color=16711680
|RECORD=13|OwnerIndex=737|IsNotAccesible=T|IndexInSheet=4|OwnerPartId=1|Location.X=80|Location.Y=623|Corner.X=80|Corner.Y=626|LineWidth=1|Color=16711680
|RECORD=13|OwnerIndex=737|IsNotAccesible=T|IndexInSheet=5|OwnerPartId=1|Location.X=80|Location.Y=616|Corner.X=80|Corner.Y=615|LineWidth=1|Color=16711680
|RECORD=41|OwnerIndex=737|IndexInSheet=6|OwnerPartId=-1|Location.X=69|Location.Y=632|Color=8388608|FontID=1|IsHidden=T|Text=Tape and Reel|Name=Packaging
|RECORD=41|OwnerIndex=737|IndexInSheet=7|OwnerPartId=-1|Location.X=69|Location.Y=632|Color=8388608|FontID=1|IsHidden=T|Text=10uF|Name=Capacitance
|RECORD=41|OwnerIndex=737|IndexInSheet=8|OwnerPartId=-1|Location.X=69|Location.Y=632|Color=8388608|FontID=1|IsHidden=T|Text=25V|Name=Voltage Rating (DC)
|RECORD=41|OwnerIndex=737|IndexInSheet=9|OwnerPartId=-1|Location.X=69|Location.Y=632|Color=8388608|FontID=1|IsHidden=T|Text=0.053inch|Name=Thickness
|RECORD=41|OwnerIndex=737|IndexInSheet=10|OwnerPartId=-1|Location.X=69|Location.Y=632|Color=8388608|FontID=1|IsHidden=T|Text=Ceramic|Name=Resistor Type
|RECORD=41|OwnerIndex=737|IndexInSheet=11|OwnerPartId=-1|Location.X=69|Location.Y=632|Color=8388608|FontID=1|IsHidden=T|Text=Yes|Name=RoHS Compliant
|RECORD=41|OwnerIndex=737|IndexInSheet=12|OwnerPartId=-1|Location.X=69|Location.Y=632|Color=8388608|FontID=1|IsHidden=T|Text=Lead Free|Name=Lead Free
|RECORD=41|OwnerIndex=737|IndexInSheet=13|OwnerPartId=-1|Location.X=69|Location.Y=632|Color=8388608|FontID=1|IsHidden=T|Text=No SVHC|Name=REACH SVHC
|RECORD=41|OwnerIndex=737|IndexInSheet=14|OwnerPartId=-1|Location.X=69|Location.Y=632|Color=8388608|FontID=1|IsHidden=T|Text=2|Name=Number of Pins
|RECORD=41|OwnerIndex=737|IndexInSheet=15|OwnerPartId=-1|Location.X=69|Location.Y=632|Color=8388608|FontID=1|IsHidden=T|Text=1|Name=Package Quantity
|RECORD=41|OwnerIndex=737|IndexInSheet=16|OwnerPartId=-1|Location.X=69|Location.Y=632|Color=8388608|FontID=1|IsHidden=T|Text=Surface Mount|Name=Mount
|RECORD=41|OwnerIndex=737|IndexInSheet=17|OwnerPartId=-1|Location.X=69|Location.Y=632|Color=8388608|FontID=1|IsHidden=T|Text=SMD/SMT|Name=Termination
|RECORD=41|OwnerIndex=737|IndexInSheet=18|OwnerPartId=-1|Location.X=69|Location.Y=632|Color=8388608|FontID=1|IsHidden=T|Text=0.049inch|Name=Width
|RECORD=41|OwnerIndex=737|IndexInSheet=19|OwnerPartId=-1|Location.X=69|Location.Y=632|Color=8388608|FontID=1|IsHidden=T|Text=85°C|Name=Max Operating Temperature
|RECORD=41|OwnerIndex=737|IndexInSheet=20|OwnerPartId=-1|Location.X=69|Location.Y=632|Color=8388608|FontID=1|IsHidden=T|Text=0.079inch|Name=Length
|RECORD=41|OwnerIndex=737|IndexInSheet=21|OwnerPartId=-1|Location.X=69|Location.Y=632|Color=8388608|FontID=1|IsHidden=T|Text=0805|Name=Case/Package
|RECORD=41|OwnerIndex=737|IndexInSheet=22|OwnerPartId=-1|Location.X=69|Location.Y=632|Color=8388608|FontID=1|IsHidden=T|Text=25V|Name=Voltage Rating
|RECORD=41|OwnerIndex=737|IndexInSheet=23|OwnerPartId=-1|Location.X=69|Location.Y=632|Color=8388608|FontID=1|IsHidden=T|Text=-55°C|Name=Min Operating Temperature
|RECORD=41|OwnerIndex=737|IndexInSheet=24|OwnerPartId=-1|Location.X=69|Location.Y=632|Color=8388608|FontID=1|IsHidden=T|Text=10%|Name=Tolerance
|RECORD=41|OwnerIndex=737|IndexInSheet=25|OwnerPartId=-1|Location.X=69|Location.Y=632|Color=8388608|FontID=1|IsHidden=T|Text=X7R|Name=Dielectric
|RECORD=41|OwnerIndex=737|IndexInSheet=26|OwnerPartId=-1|Location.X=69|Location.Y=632|Color=8388608|FontID=1|IsHidden=T|Text=2012|Name=Case Code (Metric)
|RECORD=41|OwnerIndex=737|IndexInSheet=27|OwnerPartId=-1|Location.X=69|Location.Y=632|Color=8388608|FontID=1|IsHidden=T|Text=0805|Name=Case Code (Imperial)
|RECORD=41|OwnerIndex=737|IndexInSheet=28|OwnerPartId=-1|Location.X=69|Location.Y=632|Color=8388608|FontID=1|IsHidden=T|Text=1.25mm|Name=Height
|RECORD=41|OwnerIndex=737|IndexInSheet=29|OwnerPartId=-1|Location.X=69|Location.Y=632|Color=8388608|FontID=1|IsHidden=T|Text=16V|Name=Voltage
|RECORD=41|OwnerIndex=737|IndexInSheet=30|OwnerPartId=-1|Location.X=69|Location.Y=632|Color=8388608|FontID=1|IsHidden=T|Text=M|Name=Series
|RECORD=34|OwnerIndex=737|IndexInSheet=-1|OwnerPartId=-1|Location.X=91|Location.Y=617|Color=8388608|FontID=1|Text=C34|Name=Designator|ReadOnlyState=1
|RECORD=41|OwnerIndex=737|IndexInSheet=-1|OwnerPartId=1|Location.X=91|Location.Y=607|Color=8388608|FontID=1|Text=10uF|Name=Comment
|RECORD=44|OwnerIndex=737
|RECORD=45|OwnerIndex=773|IndexInSheet=-1|UseComponentLibrary=T|ModelName=FP-MK212BG-MFG|ModelType=PCBLIB|DatafileCount=1|ModelDatafileEntity0=FP-MK212BG-MFG|ModelDatafileKind0=PCBLib|IsCurrent=T|DatalinksLocked=T|DatabaseDatalinksLocked=T
|RECORD=46|OwnerIndex=774
|RECORD=48|OwnerIndex=774
|RECORD=45|OwnerIndex=773|IndexInSheet=-1|UseComponentLibrary=T|ModelName=FP-MK212BG-IPC_C|ModelType=PCBLIB|DatafileCount=1|ModelDatafileEntity0=FP-MK212BG-IPC_C|ModelDatafileKind0=PCBLib|DatalinksLocked=T|DatabaseDatalinksLocked=T
|RECORD=46|OwnerIndex=777
|RECORD=48|OwnerIndex=777
|RECORD=45|OwnerIndex=773|IndexInSheet=-1|UseComponentLibrary=T|ModelName=FP-MK212BG-IPC_B|ModelType=PCBLIB|DatafileCount=1|ModelDatafileEntity0=FP-MK212BG-IPC_B|ModelDatafileKind0=PCBLib|DatalinksLocked=T|DatabaseDatalinksLocked=T
|RECORD=46|OwnerIndex=780
|RECORD=48|OwnerIndex=780
|RECORD=45|OwnerIndex=773|IndexInSheet=-1|UseComponentLibrary=T|ModelName=FP-MK212BG-IPC_A|ModelType=PCBLIB|DatafileCount=1|ModelDatafileEntity0=FP-MK212BG-IPC_A|ModelDatafileKind0=PCBLib|DatalinksLocked=T|DatabaseDatalinksLocked=T
|RECORD=46|OwnerIndex=783
|RECORD=48|OwnerIndex=783
|RECORD=45|OwnerIndex=773|IndexInSheet=-1|UseComponentLibrary=T|ModelName=TMK212BBJ106_G-T|ModelType=SIM|IsCurrent=T|DatalinksLocked=T|DatabaseDatalinksLocked=T
|RECORD=46|OwnerIndex=786
|RECORD=48|OwnerIndex=786
|RECORD=41|OwnerIndex=788|IndexInSheet=-1|OwnerPartId=-1|Color=8388608|FontID=1|IsHidden=T|Text=General|Name=Kind
|RECORD=41|OwnerIndex=788|IndexInSheet=-1|OwnerPartId=-1|Color=8388608|FontID=1|IsHidden=T|Text=Spice Subcircuit|Name=SubKind
|RECORD=41|OwnerIndex=788|IndexInSheet=-1|OwnerPartId=-1|Color=8388608|FontID=1|IsHidden=T|Name=Spice Prefix
|RECORD=41|OwnerIndex=788|IndexInSheet=-1|OwnerPartId=-1|Color=8388608|FontID=1|IsHidden=T|Name=Excluded Parts
|RECORD=41|OwnerIndex=788|IndexInSheet=-1|OwnerPartId=-1|Color=8388608|FontID=1|IsHidden=T|Name=Netlist
|RECORD=1|LibReference=b4654b650e69147ec39a6b967a45e02|ComponentDescription=None|PartCount=2|DisplayModeCount=1|IndexInSheet=70|OwnerPartId=-1|Location.X=180|Location.Y=630|CurrentPartId=1|LibraryPath=*|SourceLibraryName=Altium Content Vault|TargetFileName=*|AreaColor=11599871|Color=128|PartIDLocked=T|DesignItemId=CMP-14477-000079-2|AllPinCount=2
|RECORD=2|OwnerIndex=794|OwnerPartId=1|Electrical=4|PinConglomerate=49|PinLength=7|Location.X=180|Location.Y=623|Name=1|Designator=1|PinPropagationDelay=0.000000E+000
|RECORD=2|OwnerIndex=794|OwnerPartId=1|Electrical=4|PinConglomerate=51|PinLength=6|Location.X=180|Location.Y=616|Name=2|Designator=2|PinPropagationDelay=0.000000E+000
|RECORD=13|OwnerIndex=794|IsNotAccesible=T|IndexInSheet=2|OwnerPartId=1|Location.X=190|Location.Y=623|Corner.X=170|Corner.Y=623|LineWidth=1|Color=16711680
|RECORD=13|OwnerIndex=794|IsNotAccesible=T|IndexInSheet=3|OwnerPartId=1|Location.X=190|Location.Y=617|Corner.X=170|Corner.Y=617|LineWidth=1|Color=16711680
|RECORD=13|OwnerIndex=794|IsNotAccesible=T|IndexInSheet=4|OwnerPartId=1|Location.X=180|Location.Y=623|Corner.X=180|Corner.Y=626|LineWidth=1|Color=16711680
|RECORD=13|OwnerIndex=794|IsNotAccesible=T|IndexInSheet=5|OwnerPartId=1|Location.X=180|Location.Y=616|Corner.X=180|Corner.Y=615|LineWidth=1|Color=16711680
|RECORD=41|OwnerIndex=794|IndexInSheet=6|OwnerPartId=-1|Location.X=169|Location.Y=632|Color=8388608|FontID=1|IsHidden=T|Text=Tape and Reel|Name=Packaging
|RECORD=41|OwnerIndex=794|IndexInSheet=7|OwnerPartId=-1|Location.X=169|Location.Y=632|Color=8388608|FontID=1|IsHidden=T|Text=10uF|Name=Capacitance
|RECORD=41|OwnerIndex=794|IndexInSheet=8|OwnerPartId=-1|Location.X=169|Location.Y=632|Color=8388608|FontID=1|IsHidden=T|Text=25V|Name=Voltage Rating (DC)
|RECORD=41|OwnerIndex=794|IndexInSheet=9|OwnerPartId=-1|Location.X=169|Location.Y=632|Color=8388608|FontID=1|IsHidden=T|Text=0.053inch|Name=Thickness
|RECORD=41|OwnerIndex=794|IndexInSheet=10|OwnerPartId=-1|Location.X=169|Location.Y=632|Color=8388608|FontID=1|IsHidden=T|Text=Ceramic|Name=Resistor Type
|RECORD=41|OwnerIndex=794|IndexInSheet=11|OwnerPartId=-1|Location.X=169|Location.Y=632|Color=8388608|FontID=1|IsHidden=T|Text=Yes|Name=RoHS Compliant
|RECORD=41|OwnerIndex=794|IndexInSheet=12|OwnerPartId=-1|Location.X=169|Location.Y=632|Color=8388608|FontID=1|IsHidden=T|Text=Lead Free|Name=Lead Free
|RECORD=41|OwnerIndex=794|IndexInSheet=13|OwnerPartId=-1|Location.X=169|Location.Y=632|Color=8388608|FontID=1|IsHidden=T|Text=No SVHC|Name=REACH SVHC
|RECORD=41|OwnerIndex=794|IndexInSheet=14|OwnerPartId=-1|Location.X=169|Location.Y=632|Color=8388608|FontID=1|IsHidden=T|Text=2|Name=Number of Pins
|RECORD=41|OwnerIndex=794|IndexInSheet=15|OwnerPartId=-1|Location.X=169|Location.Y=632|Color=8388608|FontID=1|IsHidden=T|Text=1|Name=Package Quantity
|RECORD=41|OwnerIndex=794|IndexInSheet=16|OwnerPartId=-1|Location.X=169|Location.Y=632|Color=8388608|FontID=1|IsHidden=T|Text=Surface Mount|Name=Mount
|RECORD=41|OwnerIndex=794|IndexInSheet=17|OwnerPartId=-1|Location.X=169|Location.Y=632|Color=8388608|FontID=1|IsHidden=T|Text=SMD/SMT|Name=Termination
|RECORD=41|OwnerIndex=794|IndexInSheet=18|OwnerPartId=-1|Location.X=169|Location.Y=632|Color=8388608|FontID=1|IsHidden=T|Text=0.049inch|Name=Width
|RECORD=41|OwnerIndex=794|IndexInSheet=19|OwnerPartId=-1|Location.X=169|Location.Y=632|Color=8388608|FontID=1|IsHidden=T|Text=85°C|Name=Max Operating Temperature
|RECORD=41|OwnerIndex=794|IndexInSheet=20|OwnerPartId=-1|Location.X=169|Location.Y=632|Color=8388608|FontID=1|IsHidden=T|Text=0.079inch|Name=Length
|RECORD=41|OwnerIndex=794|IndexInSheet=21|OwnerPartId=-1|Location.X=169|Location.Y=632|Color=8388608|FontID=1|IsHidden=T|Text=0805|Name=Case/Package
|RECORD=41|OwnerIndex=794|IndexInSheet=22|OwnerPartId=-1|Location.X=169|Location.Y=632|Color=8388608|FontID=1|IsHidden=T|Text=25V|Name=Voltage Rating
|RECORD=41|OwnerIndex=794|IndexInSheet=23|OwnerPartId=-1|Location.X=169|Location.Y=632|Color=8388608|FontID=1|IsHidden=T|Text=-55°C|Name=Min Operating Temperature
|RECORD=41|OwnerIndex=794|IndexInSheet=24|OwnerPartId=-1|Location.X=169|Location.Y=632|Color=8388608|FontID=1|IsHidden=T|Text=10%|Name=Tolerance
|RECORD=41|OwnerIndex=794|IndexInSheet=25|OwnerPartId=-1|Location.X=169|Location.Y=632|Color=8388608|FontID=1|IsHidden=T|Text=X7R|Name=Dielectric
|RECORD=41|OwnerIndex=794|IndexInSheet=26|OwnerPartId=-1|Location.X=169|Location.Y=632|Color=8388608|FontID=1|IsHidden=T|Text=2012|Name=Case Code (Metric)
|RECORD=41|OwnerIndex=794|IndexInSheet=27|OwnerPartId=-1|Location.X=169|Location.Y=632|Color=8388608|FontID=1|IsHidden=T|Text=0805|Name=Case Code (Imperial)
|RECORD=41|OwnerIndex=794|IndexInSheet=28|OwnerPartId=-1|Location.X=169|Location.Y=632|Color=8388608|FontID=1|IsHidden=T|Text=1.25mm|Name=Height
|RECORD=41|OwnerIndex=794|IndexInSheet=29|OwnerPartId=-1|Location.X=169|Location.Y=632|Color=8388608|FontID=1|IsHidden=T|Text=16V|Name=Voltage
|RECORD=41|OwnerIndex=794|IndexInSheet=30|OwnerPartId=-1|Location.X=169|Location.Y=632|Color=8388608|FontID=1|IsHidden=T|Text=M|Name=Series
|RECORD=34|OwnerIndex=794|IndexInSheet=-1|OwnerPartId=-1|Location.X=191|Location.Y=617|Color=8388608|FontID=1|Text=C35|Name=Designator|ReadOnlyState=1
|RECORD=41|OwnerIndex=794|IndexInSheet=-1|OwnerPartId=1|Location.X=191|Location.Y=607|Color=8388608|FontID=1|Text=10uF|Name=Comment
|RECORD=44|OwnerIndex=794
|RECORD=45|OwnerIndex=830|IndexInSheet=-1|UseComponentLibrary=T|ModelName=FP-MK212BG-MFG|ModelType=PCBLIB|DatafileCount=1|ModelDatafileEntity0=FP-MK212BG-MFG|ModelDatafileKind0=PCBLib|IsCurrent=T|DatalinksLocked=T|DatabaseDatalinksLocked=T
|RECORD=46|OwnerIndex=831
|RECORD=48|OwnerIndex=831
|RECORD=45|OwnerIndex=830|IndexInSheet=-1|UseComponentLibrary=T|ModelName=FP-MK212BG-IPC_C|ModelType=PCBLIB|DatafileCount=1|ModelDatafileEntity0=FP-MK212BG-IPC_C|ModelDatafileKind0=PCBLib|DatalinksLocked=T|DatabaseDatalinksLocked=T
|RECORD=46|OwnerIndex=834
|RECORD=48|OwnerIndex=834
|RECORD=45|OwnerIndex=830|IndexInSheet=-1|UseComponentLibrary=T|ModelName=FP-MK212BG-IPC_B|ModelType=PCBLIB|DatafileCount=1|ModelDatafileEntity0=FP-MK212BG-IPC_B|ModelDatafileKind0=PCBLib|DatalinksLocked=T|DatabaseDatalinksLocked=T
|RECORD=46|OwnerIndex=837
|RECORD=48|OwnerIndex=837
|RECORD=45|OwnerIndex=830|IndexInSheet=-1|UseComponentLibrary=T|ModelName=FP-MK212BG-IPC_A|ModelType=PCBLIB|DatafileCount=1|ModelDatafileEntity0=FP-MK212BG-IPC_A|ModelDatafileKind0=PCBLib|DatalinksLocked=T|DatabaseDatalinksLocked=T
|RECORD=46|OwnerIndex=840
|RECORD=48|OwnerIndex=840
|RECORD=45|OwnerIndex=830|IndexInSheet=-1|UseComponentLibrary=T|ModelName=TMK212BBJ106_G-T|ModelType=SIM|IsCurrent=T|DatalinksLocked=T|DatabaseDatalinksLocked=T
|RECORD=46|OwnerIndex=843
|RECORD=48|OwnerIndex=843
|RECORD=41|OwnerIndex=845|IndexInSheet=-1|OwnerPartId=-1|Color=8388608|FontID=1|IsHidden=T|Text=General|Name=Kind
|RECORD=41|OwnerIndex=845|IndexInSheet=-1|OwnerPartId=-1|Color=8388608|FontID=1|IsHidden=T|Text=Spice Subcircuit|Name=SubKind
|RECORD=41|OwnerIndex=845|IndexInSheet=-1|OwnerPartId=-1|Color=8388608|FontID=1|IsHidden=T|Name=Spice Prefix
|RECORD=41|OwnerIndex=845|IndexInSheet=-1|OwnerPartId=-1|Color=8388608|FontID=1|IsHidden=T|Name=Excluded Parts
|RECORD=41|OwnerIndex=845|IndexInSheet=-1|OwnerPartId=-1|Color=8388608|FontID=1|IsHidden=T|Name=Netlist
|RECORD=1|LibReference=Header 6X2A|ComponentDescription=Header, 6-Pin, Dual row|PartCount=2|DisplayModeCount=1|IndexInSheet=71|OwnerPartId=-1|Location.X=200|Location.Y=160|CurrentPartId=1|SourceLibraryName=Miscellaneous Connectors.IntLib|TargetFileName=*|AreaColor=11599871|Color=128|PartIDLocked=F|DesignItemId=Header 6X2A|AllPinCount=12
|RECORD=14|OwnerIndex=851|IsNotAccesible=T|OwnerPartId=1|Location.X=200|Location.Y=90|Corner.X=240|Corner.Y=160|Color=128|AreaColor=11599871|IsSolid=T
|RECORD=2|OwnerIndex=851|OwnerPartId=1|FormalType=1|Electrical=4|PinConglomerate=42|PinLength=20|Location.X=200|Location.Y=150|Name=1|Designator=1|PinPropagationDelay=0.000000E+000
|RECORD=2|OwnerIndex=851|OwnerPartId=1|FormalType=1|Electrical=4|PinConglomerate=42|PinLength=20|Location.X=200|Location.Y=140|Name=2|Designator=2|PinPropagationDelay=0.000000E+000
|RECORD=2|OwnerIndex=851|OwnerPartId=1|FormalType=1|Electrical=4|PinConglomerate=42|PinLength=20|Location.X=200|Location.Y=130|Name=3|Designator=3|PinPropagationDelay=0.000000E+000
|RECORD=2|OwnerIndex=851|OwnerPartId=1|FormalType=1|Electrical=4|PinConglomerate=42|PinLength=20|Location.X=200|Location.Y=120|Name=4|Designator=4|PinPropagationDelay=0.000000E+000
|RECORD=2|OwnerIndex=851|OwnerPartId=1|FormalType=1|Electrical=4|PinConglomerate=42|PinLength=20|Location.X=200|Location.Y=110|Name=5|Designator=5|PinPropagationDelay=0.000000E+000
|RECORD=2|OwnerIndex=851|OwnerPartId=1|FormalType=1|Electrical=4|PinConglomerate=42|PinLength=20|Location.X=200|Location.Y=100|Name=6|Designator=6|PinPropagationDelay=0.000000E+000
|RECORD=2|OwnerIndex=851|OwnerPartId=1|FormalType=1|Electrical=4|PinConglomerate=40|PinLength=20|Location.X=240|Location.Y=150|Name=7|Designator=7|PinPropagationDelay=0.000000E+000
|RECORD=2|OwnerIndex=851|OwnerPartId=1|FormalType=1|Electrical=4|PinConglomerate=40|PinLength=20|Location.X=240|Location.Y=140|Name=8|Designator=8|PinPropagationDelay=0.000000E+000
|RECORD=2|OwnerIndex=851|OwnerPartId=1|FormalType=1|Electrical=4|PinConglomerate=40|PinLength=20|Location.X=240|Location.Y=130|Name=9|Designator=9|PinPropagationDelay=0.000000E+000
|RECORD=2|OwnerIndex=851|OwnerPartId=1|FormalType=1|Electrical=4|PinConglomerate=40|PinLength=20|Location.X=240|Location.Y=120|Name=10|Designator=10|PinPropagationDelay=0.000000E+000
|RECORD=2|OwnerIndex=851|OwnerPartId=1|FormalType=1|Electrical=4|PinConglomerate=40|PinLength=20|Location.X=240|Location.Y=110|Name=11|Designator=11|PinPropagationDelay=0.000000E+000
|RECORD=2|OwnerIndex=851|OwnerPartId=1|FormalType=1|Electrical=4|PinConglomerate=40|PinLength=20|Location.X=240|Location.Y=100|Name=12|Designator=12|PinPropagationDelay=0.000000E+000
|RECORD=41|OwnerIndex=851|IndexInSheet=13|OwnerPartId=-1|Location.X=200|Location.Y=160|Color=8388608|FontID=1|IsHidden=T|Text=17-Jul-2002|Name=LatestRevisionDate
|RECORD=41|OwnerIndex=851|IndexInSheet=14|OwnerPartId=-1|Location.X=200|Location.Y=160|Color=8388608|FontID=1|IsHidden=T|Text=Re-released for DXP Platform.|Name=LatestRevisionNote
|RECORD=41|OwnerIndex=851|IndexInSheet=15|OwnerPartId=-1|Location.X=200|Location.Y=160|Color=8388608|FontID=1|IsHidden=T|Text=Altium Limited|Name=Publisher
|RECORD=34|OwnerIndex=851|IndexInSheet=-1|OwnerPartId=-1|Location.X=200|Location.Y=160|Color=8388608|FontID=1|Text=P3|Name=Designator|ReadOnlyState=1
|RECORD=41|OwnerIndex=851|IndexInSheet=-1|OwnerPartId=-1|Location.X=200|Location.Y=80|Color=8388608|FontID=1|Text=EXT GPIO|Name=Comment|ReadOnlyState=1
|RECORD=44|OwnerIndex=851
|RECORD=45|OwnerIndex=882|IndexInSheet=-1|Description=Connector; Header; 6x2 Position|UseComponentLibrary=T|ModelName=HDR2X6_CEN|ModelType=PCBLIB|DatafileCount=1|ModelDatafileEntity0=HDR2X6_CEN|ModelDatafileKind0=PCBLib|IsCurrent=T|DatalinksLocked=T|DatabaseDatalinksLocked=T|IntegratedModel=T|DatabaseModel=T
|RECORD=46|OwnerIndex=883
|RECORD=48|OwnerIndex=883
|RECORD=45|OwnerIndex=882|IndexInSheet=-1|UseComponentLibrary=T|ModelName=Connector|ModelType=SI|IsCurrent=T|DatalinksLocked=T|DatabaseDatalinksLocked=T|IntegratedModel=T|DatabaseModel=T
|RECORD=46|OwnerIndex=886
|RECORD=48|OwnerIndex=886
|RECORD=41|OwnerIndex=888|IndexInSheet=-1|OwnerPartId=-1|Color=8388608|FontID=1|Text=Connector|Name=Type
|RECORD=41|OwnerIndex=888|IndexInSheet=-1|OwnerPartId=-1|Color=8388608|FontID=1|Name=Tech
|RECORD=17|IndexInSheet=72|OwnerPartId=-1|ShowNetName=T|Location.X=160|Location.Y=190|Orientation=1|Color=128|FontID=1|Text=+3.3V
|RECORD=17|IndexInSheet=73|OwnerPartId=-1|Style=4|ShowNetName=T|Location.X=300|Location.Y=70|Orientation=3|Color=128|FontID=1|Text=GND
|RECORD=17|IndexInSheet=74|OwnerPartId=-1|Style=4|ShowNetName=T|Location.X=140|Location.Y=70|Orientation=3|Color=128|FontID=1|Text=GND
|RECORD=17|IndexInSheet=75|OwnerPartId=-1|ShowNetName=T|Location.X=280|Location.Y=190|Orientation=1|Color=128|FontID=1|Text=+3.3V
|RECORD=17|IndexInSheet=76|OwnerPartId=-1|ShowNetName=T|Location.X=110|Location.Y=150|Orientation=2|Color=255|FontID=1|Text=EXT_GPIO_1|IsCrossSheetConnector=T
|RECORD=17|IndexInSheet=77|OwnerPartId=-1|ShowNetName=T|Location.X=110|Location.Y=140|Orientation=2|Color=255|FontID=1|Text=EXT_GPIO_2|IsCrossSheetConnector=T
|RECORD=17|IndexInSheet=78|OwnerPartId=-1|ShowNetName=T|Location.X=110|Location.Y=130|Orientation=2|Color=255|FontID=1|Text=EXT_GPIO_3|IsCrossSheetConnector=T
|RECORD=17|IndexInSheet=79|OwnerPartId=-1|ShowNetName=T|Location.X=110|Location.Y=120|Orientation=2|Color=255|FontID=1|Text=EXT_GPIO_4|IsCrossSheetConnector=T
|RECORD=17|IndexInSheet=80|OwnerPartId=-1|ShowNetName=T|Location.X=330|Location.Y=150|Color=255|FontID=1|Text=EXT_GPIO_7|IsCrossSheetConnector=T
|RECORD=17|IndexInSheet=81|OwnerPartId=-1|ShowNetName=T|Location.X=330|Location.Y=140|Color=255|FontID=1|Text=EXT_GPIO_8|IsCrossSheetConnector=T
|RECORD=17|IndexInSheet=82|OwnerPartId=-1|ShowNetName=T|Location.X=330|Location.Y=130|Color=255|FontID=1|Text=EXT_GPIO_9|IsCrossSheetConnector=T
|RECORD=17|IndexInSheet=83|OwnerPartId=-1|ShowNetName=T|Location.X=330|Location.Y=120|Color=255|FontID=1|Text=EXT_GPIO_10|IsCrossSheetConnector=T
|RECORD=4|IndexInSheet=84|OwnerPartId=-1|Location.X=150|Location.Y=220|Color=8388608|FontID=7|Text=EXTERNAL GPIO
|RECORD=41|IndexInSheet=85|OwnerPartId=-1|Color=8388608|FontID=1|IsHidden=T|Text=*|Name=CurrentTime|ReadOnlyState=1
|RECORD=41|IndexInSheet=86|OwnerPartId=-1|Color=8388608|FontID=1|IsHidden=T|Text=*|Name=CurrentDate|ReadOnlyState=1
|RECORD=41|IndexInSheet=87|OwnerPartId=-1|Color=8388608|FontID=1|IsHidden=T|Text=*|Name=Time|ReadOnlyState=1
|RECORD=41|IndexInSheet=88|OwnerPartId=-1|Color=8388608|FontID=1|IsHidden=T|Text=*|Name=Date|ReadOnlyState=1
|RECORD=41|IndexInSheet=89|OwnerPartId=-1|Color=8388608|FontID=1|IsHidden=T|Text=*|Name=DocumentFullPathAndName|ReadOnlyState=1
|RECORD=41|IndexInSheet=90|OwnerPartId=-1|Color=8388608|FontID=1|IsHidden=T|Text=*|Name=DocumentName|ReadOnlyState=1
|RECORD=41|IndexInSheet=91|OwnerPartId=-1|Color=8388608|FontID=1|IsHidden=T|Text=*|Name=ModifiedDate|ReadOnlyState=1
|RECORD=41|IndexInSheet=92|OwnerPartId=-1|Color=8388608|FontID=1|IsHidden=T|Text=*|Name=ApprovedBy|ReadOnlyState=1
|RECORD=41|IndexInSheet=93|OwnerPartId=-1|Color=8388608|FontID=1|IsHidden=T|Text=*|Name=CheckedBy|ReadOnlyState=1
|RECORD=41|IndexInSheet=94|OwnerPartId=-1|Color=8388608|FontID=1|IsHidden=T|Text=*|Name=Author|ReadOnlyState=1
|RECORD=41|IndexInSheet=95|OwnerPartId=-1|Color=8388608|FontID=1|IsHidden=T|Text=*|Name=CompanyName|ReadOnlyState=1
|RECORD=41|IndexInSheet=96|OwnerPartId=-1|Color=8388608|FontID=1|IsHidden=T|Text=*|Name=DrawnBy|ReadOnlyState=1
|RECORD=41|IndexInSheet=97|OwnerPartId=-1|Color=8388608|FontID=1|IsHidden=T|Text=*|Name=Engineer|ReadOnlyState=1
|RECORD=41|IndexInSheet=98|OwnerPartId=-1|Color=8388608|FontID=1|IsHidden=T|Text=*|Name=Organization|ReadOnlyState=1
|RECORD=41|IndexInSheet=99|OwnerPartId=-1|Color=8388608|FontID=1|IsHidden=T|Text=*|Name=Address1|ReadOnlyState=1
|RECORD=41|IndexInSheet=100|OwnerPartId=-1|Color=8388608|FontID=1|IsHidden=T|Text=*|Name=Address2|ReadOnlyState=1
|RECORD=41|IndexInSheet=101|OwnerPartId=-1|Color=8388608|FontID=1|IsHidden=T|Text=*|Name=Address3|ReadOnlyState=1
|RECORD=41|IndexInSheet=102|OwnerPartId=-1|Color=8388608|FontID=1|IsHidden=T|Text=*|Name=Address4|ReadOnlyState=1
|RECORD=41|IndexInSheet=103|OwnerPartId=-1|Color=8388608|FontID=1|IsHidden=T|Text=*|Name=Title|ReadOnlyState=1
|RECORD=41|IndexInSheet=104|OwnerPartId=-1|Color=8388608|FontID=1|IsHidden=T|Text=*|Name=DocumentNumber|ReadOnlyState=1
|RECORD=41|IndexInSheet=105|OwnerPartId=-1|Color=8388608|FontID=1|IsHidden=T|Text=*|Name=Revision|ReadOnlyState=1
|RECORD=41|IndexInSheet=106|OwnerPartId=-1|Color=8388608|FontID=1|IsHidden=T|Text=*|Name=SheetNumber|ReadOnlyState=1
|RECORD=41|IndexInSheet=107|OwnerPartId=-1|Color=8388608|FontID=1|IsHidden=T|Text=*|Name=SheetTotal|ReadOnlyState=1
|RECORD=41|IndexInSheet=108|OwnerPartId=-1|Color=8388608|FontID=1|IsHidden=T|Text=*|Name=Rule|ReadOnlyState=1
|RECORD=41|IndexInSheet=109|OwnerPartId=-1|Color=8388608|FontID=1|IsHidden=T|Text=*|Name=ImagePath|ReadOnlyState=1
|RECORD=41|IndexInSheet=110|OwnerPartId=-1|Color=8388608|FontID=1|IsHidden=T|Text=*|Name=ProjectName|ReadOnlyState=1
|RECORD=41|IndexInSheet=111|OwnerPartId=-1|Color=8388608|FontID=1|IsHidden=T|Text=*|Name=Application_BuildNumber|ReadOnlyState=1
|RECORD=1|LibReference=GNSS Standoff|PartCount=2|DisplayModeCount=1|IndexInSheet=112|OwnerPartId=-1|Location.X=1020|Location.Y=980|CurrentPartId=1|LibraryPath=*|SourceLibraryName=FPGA_CONN.SchLib|TargetFileName=*|AreaColor=11599871|Color=128|PartIDLocked=T|NotUseDBTableName=T|DesignItemId=GNSS Standoff
|RECORD=12|OwnerIndex=931|IsNotAccesible=T|OwnerPartId=1|Location.X=1020|Location.Y=980|Radius=9|Radius_Frac=45302|LineWidth=1|EndAngle=360.000|Color=16711680
|RECORD=41|OwnerIndex=931|IndexInSheet=1|OwnerPartId=-1|Location.X=1010|Location.X_Frac=54698|Location.Y=995|Color=8388608|FontID=1|IsHidden=T|Text=Digi-Key|Name=Supplier 1|ReadOnlyState=3
|RECORD=41|OwnerIndex=931|IndexInSheet=2|OwnerPartId=-1|Location.X=1010|Location.X_Frac=54698|Location.Y=950|Location.Y_Frac=54698|Color=8388608|FontID=1|Text=36-24393-ND|Name=Supplier Part Number 1|ReadOnlyState=3
|RECORD=34|OwnerIndex=931|IndexInSheet=-1|OwnerPartId=-1|Location.X=1010|Location.X_Frac=54698|Location.Y=989|Location.Y_Frac=45302|Color=8388608|FontID=1|Text=J5|Name=Designator|ReadOnlyState=1
|RECORD=41|OwnerIndex=931|IndexInSheet=-1|OwnerPartId=-1|Location.X=1010|Location.X_Frac=54698|Location.Y=960|Location.Y_Frac=54698|Color=8388608|FontID=1|Text=GNSS Standoff|Name=Comment
|RECORD=44|OwnerIndex=931
|RECORD=1|LibReference=GNSS Standoff|PartCount=2|DisplayModeCount=1|IndexInSheet=113|OwnerPartId=-1|Location.X=1020|Location.Y=930|CurrentPartId=1|LibraryPath=*|SourceLibraryName=FPGA_CONN.SchLib|TargetFileName=*|AreaColor=11599871|Color=128|PartIDLocked=T|NotUseDBTableName=T|DesignItemId=GNSS Standoff
|RECORD=12|OwnerIndex=938|IsNotAccesible=T|OwnerPartId=1|Location.X=1020|Location.Y=930|Radius=9|Radius_Frac=45302|LineWidth=1|EndAngle=360.000|Color=16711680
|RECORD=41|OwnerIndex=938|IndexInSheet=1|OwnerPartId=-1|Location.X=1010|Location.X_Frac=54698|Location.Y=945|Color=8388608|FontID=1|IsHidden=T|Text=Digi-Key|Name=Supplier 1|ReadOnlyState=3
|RECORD=41|OwnerIndex=938|IndexInSheet=2|OwnerPartId=-1|Location.X=1010|Location.X_Frac=54698|Location.Y=900|Location.Y_Frac=54698|Color=8388608|FontID=1|Text=36-24393-ND|Name=Supplier Part Number 1|ReadOnlyState=3
|RECORD=34|OwnerIndex=938|IndexInSheet=-1|OwnerPartId=-1|Location.X=1010|Location.X_Frac=54698|Location.Y=939|Location.Y_Frac=45302|Color=8388608|FontID=1|Text=J7|Name=Designator|ReadOnlyState=1
|RECORD=41|OwnerIndex=938|IndexInSheet=-1|OwnerPartId=-1|Location.X=1010|Location.X_Frac=54698|Location.Y=910|Location.Y_Frac=54698|Color=8388608|FontID=1|Text=GNSS Standoff|Name=Comment
|RECORD=44|OwnerIndex=938
|RECORD=1|LibReference=GNSS Standoff|PartCount=2|DisplayModeCount=1|IndexInSheet=114|OwnerPartId=-1|Location.X=1020|Location.Y=880|CurrentPartId=1|LibraryPath=*|SourceLibraryName=FPGA_CONN.SchLib|TargetFileName=*|AreaColor=11599871|Color=128|PartIDLocked=T|NotUseDBTableName=T|DesignItemId=GNSS Standoff
|RECORD=12|OwnerIndex=945|IsNotAccesible=T|OwnerPartId=1|Location.X=1020|Location.Y=880|Radius=9|Radius_Frac=45302|LineWidth=1|EndAngle=360.000|Color=16711680
|RECORD=41|OwnerIndex=945|IndexInSheet=1|OwnerPartId=-1|Location.X=1010|Location.X_Frac=54698|Location.Y=895|Color=8388608|FontID=1|IsHidden=T|Text=Digi-Key|Name=Supplier 1|ReadOnlyState=3
|RECORD=41|OwnerIndex=945|IndexInSheet=2|OwnerPartId=-1|Location.X=1010|Location.X_Frac=54698|Location.Y=850|Location.Y_Frac=54698|Color=8388608|FontID=1|Text=36-24393-ND|Name=Supplier Part Number 1|ReadOnlyState=3
|RECORD=34|OwnerIndex=945|IndexInSheet=-1|OwnerPartId=-1|Location.X=1010|Location.X_Frac=54698|Location.Y=889|Location.Y_Frac=45302|Color=8388608|FontID=1|Text=J8|Name=Designator|ReadOnlyState=1
|RECORD=41|OwnerIndex=945|IndexInSheet=-1|OwnerPartId=-1|Location.X=1010|Location.X_Frac=54698|Location.Y=860|Location.Y_Frac=54698|Color=8388608|FontID=1|Text=GNSS Standoff|Name=Comment
|RECORD=44|OwnerIndex=945
|RECORD=1|LibReference=GNSS Standoff|PartCount=2|DisplayModeCount=1|IndexInSheet=115|OwnerPartId=-1|Location.X=1020|Location.Y=830|CurrentPartId=1|LibraryPath=*|SourceLibraryName=FPGA_CONN.SchLib|TargetFileName=*|AreaColor=11599871|Color=128|PartIDLocked=T|NotUseDBTableName=T|DesignItemId=GNSS Standoff
|RECORD=12|OwnerIndex=952|IsNotAccesible=T|OwnerPartId=1|Location.X=1020|Location.Y=830|Radius=9|Radius_Frac=45302|LineWidth=1|EndAngle=360.000|Color=16711680
|RECORD=41|OwnerIndex=952|IndexInSheet=1|OwnerPartId=-1|Location.X=1010|Location.X_Frac=54698|Location.Y=845|Color=8388608|FontID=1|IsHidden=T|Text=Digi-Key|Name=Supplier 1|ReadOnlyState=3
|RECORD=41|OwnerIndex=952|IndexInSheet=2|OwnerPartId=-1|Location.X=1010|Location.X_Frac=54698|Location.Y=800|Location.Y_Frac=54698|Color=8388608|FontID=1|Text=36-24393-ND|Name=Supplier Part Number 1|ReadOnlyState=3
|RECORD=34|OwnerIndex=952|IndexInSheet=-1|OwnerPartId=-1|Location.X=1010|Location.X_Frac=54698|Location.Y=839|Location.Y_Frac=45302|Color=8388608|FontID=1|Text=J9|Name=Designator|ReadOnlyState=1
|RECORD=41|OwnerIndex=952|IndexInSheet=-1|OwnerPartId=-1|Location.X=1010|Location.X_Frac=54698|Location.Y=810|Location.Y_Frac=54698|Color=8388608|FontID=1|Text=GNSS Standoff|Name=Comment
|RECORD=44|OwnerIndex=952
|RECORD=1|LibReference=GNSS Standoff|PartCount=2|DisplayModeCount=1|IndexInSheet=116|OwnerPartId=-1|Location.X=790|Location.Y=640|CurrentPartId=1|LibraryPath=*|SourceLibraryName=FPGA_CONN.SchLib|TargetFileName=*|AreaColor=11599871|Color=128|PartIDLocked=T|NotUseDBTableName=T|DesignItemId=GNSS Standoff
|RECORD=12|OwnerIndex=959|IsNotAccesible=T|OwnerPartId=1|Location.X=790|Location.Y=640|Radius=9|Radius_Frac=45302|LineWidth=1|EndAngle=360.000|Color=16711680
|RECORD=41|OwnerIndex=959|IndexInSheet=1|OwnerPartId=-1|Location.X=780|Location.X_Frac=54698|Location.Y=655|Color=8388608|FontID=1|IsHidden=T|Text=Digi-Key|Name=Supplier 1|ReadOnlyState=3
|RECORD=41|OwnerIndex=959|IndexInSheet=2|OwnerPartId=-1|Location.X=780|Location.X_Frac=54698|Location.Y=610|Location.Y_Frac=54698|Color=8388608|FontID=1|Text=36-24393-ND|Name=Supplier Part Number 1|ReadOnlyState=3
|RECORD=34|OwnerIndex=959|IndexInSheet=-1|OwnerPartId=-1|Location.X=780|Location.X_Frac=54698|Location.Y=649|Location.Y_Frac=45302|Color=8388608|FontID=1|Text=J10|Name=Designator|ReadOnlyState=1
|RECORD=41|OwnerIndex=959|IndexInSheet=-1|OwnerPartId=-1|Location.X=780|Location.X_Frac=54698|Location.Y=620|Location.Y_Frac=54698|Color=8388608|FontID=1|Text=GNSS Standoff|Name=Comment
|RECORD=44|OwnerIndex=959
|RECORD=1|LibReference=GNSS Standoff|PartCount=2|DisplayModeCount=1|IndexInSheet=117|OwnerPartId=-1|Location.X=790|Location.Y=590|CurrentPartId=1|LibraryPath=*|SourceLibraryName=FPGA_CONN.SchLib|TargetFileName=*|AreaColor=11599871|Color=128|PartIDLocked=T|NotUseDBTableName=T|DesignItemId=GNSS Standoff
|RECORD=12|OwnerIndex=966|IsNotAccesible=T|OwnerPartId=1|Location.X=790|Location.Y=590|Radius=9|Radius_Frac=45302|LineWidth=1|EndAngle=360.000|Color=16711680
|RECORD=41|OwnerIndex=966|IndexInSheet=1|OwnerPartId=-1|Location.X=780|Location.X_Frac=54698|Location.Y=605|Color=8388608|FontID=1|IsHidden=T|Text=Digi-Key|Name=Supplier 1|ReadOnlyState=3
|RECORD=41|OwnerIndex=966|IndexInSheet=2|OwnerPartId=-1|Location.X=780|Location.X_Frac=54698|Location.Y=560|Location.Y_Frac=54698|Color=8388608|FontID=1|Text=36-24393-ND|Name=Supplier Part Number 1|ReadOnlyState=3
|RECORD=34|OwnerIndex=966|IndexInSheet=-1|OwnerPartId=-1|Location.X=780|Location.X_Frac=54698|Location.Y=599|Location.Y_Frac=45302|Color=8388608|FontID=1|Text=J11|Name=Designator|ReadOnlyState=1
|RECORD=41|OwnerIndex=966|IndexInSheet=-1|OwnerPartId=-1|Location.X=780|Location.X_Frac=54698|Location.Y=570|Location.Y_Frac=54698|Color=8388608|FontID=1|Text=GNSS Standoff|Name=Comment
|RECORD=44|OwnerIndex=966
|RECORD=1|LibReference=GNSS Standoff|PartCount=2|DisplayModeCount=1|IndexInSheet=118|OwnerPartId=-1|Location.X=790|Location.Y=540|CurrentPartId=1|LibraryPath=*|SourceLibraryName=FPGA_CONN.SchLib|TargetFileName=*|AreaColor=11599871|Color=128|PartIDLocked=T|NotUseDBTableName=T|DesignItemId=GNSS Standoff
|RECORD=12|OwnerIndex=973|IsNotAccesible=T|OwnerPartId=1|Location.X=790|Location.Y=540|Radius=9|Radius_Frac=45302|LineWidth=1|EndAngle=360.000|Color=16711680
|RECORD=41|OwnerIndex=973|IndexInSheet=1|OwnerPartId=-1|Location.X=780|Location.X_Frac=54698|Location.Y=555|Color=8388608|FontID=1|IsHidden=T|Text=Digi-Key|Name=Supplier 1|ReadOnlyState=3
|RECORD=41|OwnerIndex=973|IndexInSheet=2|OwnerPartId=-1|Location.X=780|Location.X_Frac=54698|Location.Y=510|Location.Y_Frac=54698|Color=8388608|FontID=1|Text=36-24393-ND|Name=Supplier Part Number 1|ReadOnlyState=3
|RECORD=34|OwnerIndex=973|IndexInSheet=-1|OwnerPartId=-1|Location.X=780|Location.X_Frac=54698|Location.Y=549|Location.Y_Frac=45302|Color=8388608|FontID=1|Text=J12|Name=Designator|ReadOnlyState=1
|RECORD=41|OwnerIndex=973|IndexInSheet=-1|OwnerPartId=-1|Location.X=780|Location.X_Frac=54698|Location.Y=520|Location.Y_Frac=54698|Color=8388608|FontID=1|Text=GNSS Standoff|Name=Comment
|RECORD=44|OwnerIndex=973
|RECORD=1|LibReference=GNSS Standoff|PartCount=2|DisplayModeCount=1|IndexInSheet=119|OwnerPartId=-1|Location.X=790|Location.Y=490|CurrentPartId=1|LibraryPath=*|SourceLibraryName=FPGA_CONN.SchLib|TargetFileName=*|AreaColor=11599871|Color=128|PartIDLocked=T|NotUseDBTableName=T|DesignItemId=GNSS Standoff
|RECORD=12|OwnerIndex=980|IsNotAccesible=T|OwnerPartId=1|Location.X=790|Location.Y=490|Radius=9|Radius_Frac=45302|LineWidth=1|EndAngle=360.000|Color=16711680
|RECORD=41|OwnerIndex=980|IndexInSheet=1|OwnerPartId=-1|Location.X=780|Location.X_Frac=54698|Location.Y=505|Color=8388608|FontID=1|IsHidden=T|Text=Digi-Key|Name=Supplier 1|ReadOnlyState=3
|RECORD=41|OwnerIndex=980|IndexInSheet=2|OwnerPartId=-1|Location.X=780|Location.X_Frac=54698|Location.Y=460|Location.Y_Frac=54698|Color=8388608|FontID=1|Text=36-24393-ND|Name=Supplier Part Number 1|ReadOnlyState=3
|RECORD=34|OwnerIndex=980|IndexInSheet=-1|OwnerPartId=-1|Location.X=780|Location.X_Frac=54698|Location.Y=499|Location.Y_Frac=45302|Color=8388608|FontID=1|Text=J14|Name=Designator|ReadOnlyState=1
|RECORD=41|OwnerIndex=980|IndexInSheet=-1|OwnerPartId=-1|Location.X=780|Location.X_Frac=54698|Location.Y=470|Location.Y_Frac=54698|Color=8388608|FontID=1|Text=GNSS Standoff|Name=Comment
|RECORD=44|OwnerIndex=980
|RECORD=1|LibReference=M3 screw|PartCount=2|DisplayModeCount=1|IndexInSheet=120|OwnerPartId=-1|Location.X=1100|Location.Y=980|CurrentPartId=1|LibraryPath=*|SourceLibraryName=FPGA_CONN.SchLib|TargetFileName=*|AreaColor=11599871|Color=128|PartIDLocked=T|NotUseDBTableName=T|DesignItemId=M3 screw
|RECORD=12|OwnerIndex=987|IsNotAccesible=T|OwnerPartId=1|Location.X=1100|Location.Y=980|Radius=9|Radius_Frac=18136|LineWidth=1|EndAngle=360.000|Color=16711680
|RECORD=41|OwnerIndex=987|IndexInSheet=1|OwnerPartId=-1|Location.X=1090|Location.X_Frac=81864|Location.Y=995|Color=8388608|FontID=1|IsHidden=T|Text=Digi-Key|Name=Supplier 1|ReadOnlyState=3
|RECORD=41|OwnerIndex=987|IndexInSheet=2|OwnerPartId=-1|Location.X=1090|Location.X_Frac=81864|Location.Y=950|Location.Y_Frac=81864|Color=8388608|FontID=1|Text=335-1156-ND|Name=Supplier Part Number 1|ReadOnlyState=3
|RECORD=34|OwnerIndex=987|IndexInSheet=-1|OwnerPartId=-1|Location.X=1090|Location.X_Frac=81864|Location.Y=989|Location.Y_Frac=18136|Color=8388608|FontID=1|Text=J15|Name=Designator|ReadOnlyState=1
|RECORD=41|OwnerIndex=987|IndexInSheet=-1|OwnerPartId=-1|Location.X=1090|Location.X_Frac=81864|Location.Y=960|Location.Y_Frac=81864|Color=8388608|FontID=1|Text=M3 screw|Name=Comment
|RECORD=44|OwnerIndex=987
|RECORD=1|LibReference=M3 screw|PartCount=2|DisplayModeCount=1|IndexInSheet=121|OwnerPartId=-1|Location.X=1100|Location.Y=930|CurrentPartId=1|LibraryPath=*|SourceLibraryName=FPGA_CONN.SchLib|TargetFileName=*|AreaColor=11599871|Color=128|PartIDLocked=T|NotUseDBTableName=T|DesignItemId=M3 screw
|RECORD=12|OwnerIndex=994|IsNotAccesible=T|OwnerPartId=1|Location.X=1100|Location.Y=930|Radius=9|Radius_Frac=18136|LineWidth=1|EndAngle=360.000|Color=16711680
|RECORD=41|OwnerIndex=994|IndexInSheet=1|OwnerPartId=-1|Location.X=1090|Location.X_Frac=81864|Location.Y=945|Color=8388608|FontID=1|IsHidden=T|Text=Digi-Key|Name=Supplier 1|ReadOnlyState=3
|RECORD=41|OwnerIndex=994|IndexInSheet=2|OwnerPartId=-1|Location.X=1090|Location.X_Frac=81864|Location.Y=900|Location.Y_Frac=81864|Color=8388608|FontID=1|Text=335-1156-ND|Name=Supplier Part Number 1|ReadOnlyState=3
|RECORD=34|OwnerIndex=994|IndexInSheet=-1|OwnerPartId=-1|Location.X=1090|Location.X_Frac=81864|Location.Y=939|Location.Y_Frac=18136|Color=8388608|FontID=1|Text=J16|Name=Designator|ReadOnlyState=1
|RECORD=41|OwnerIndex=994|IndexInSheet=-1|OwnerPartId=-1|Location.X=1090|Location.X_Frac=81864|Location.Y=910|Location.Y_Frac=81864|Color=8388608|FontID=1|Text=M3 screw|Name=Comment
|RECORD=44|OwnerIndex=994
|RECORD=1|LibReference=M3 screw|PartCount=2|DisplayModeCount=1|IndexInSheet=122|OwnerPartId=-1|Location.X=1100|Location.Y=880|CurrentPartId=1|LibraryPath=*|SourceLibraryName=FPGA_CONN.SchLib|TargetFileName=*|AreaColor=11599871|Color=128|PartIDLocked=T|NotUseDBTableName=T|DesignItemId=M3 screw
|RECORD=12|OwnerIndex=1001|IsNotAccesible=T|OwnerPartId=1|Location.X=1100|Location.Y=880|Radius=9|Radius_Frac=18136|LineWidth=1|EndAngle=360.000|Color=16711680
|RECORD=41|OwnerIndex=1001|IndexInSheet=1|OwnerPartId=-1|Location.X=1090|Location.X_Frac=81864|Location.Y=895|Color=8388608|FontID=1|IsHidden=T|Text=Digi-Key|Name=Supplier 1|ReadOnlyState=3
|RECORD=41|OwnerIndex=1001|IndexInSheet=2|OwnerPartId=-1|Location.X=1090|Location.X_Frac=81864|Location.Y=850|Location.Y_Frac=81864|Color=8388608|FontID=1|Text=335-1156-ND|Name=Supplier Part Number 1|ReadOnlyState=3
|RECORD=34|OwnerIndex=1001|IndexInSheet=-1|OwnerPartId=-1|Location.X=1090|Location.X_Frac=81864|Location.Y=889|Location.Y_Frac=18136|Color=8388608|FontID=1|Text=J17|Name=Designator|ReadOnlyState=1
|RECORD=41|OwnerIndex=1001|IndexInSheet=-1|OwnerPartId=-1|Location.X=1090|Location.X_Frac=81864|Location.Y=860|Location.Y_Frac=81864|Color=8388608|FontID=1|Text=M3 screw|Name=Comment
|RECORD=44|OwnerIndex=1001
|RECORD=1|LibReference=M3 screw|PartCount=2|DisplayModeCount=1|IndexInSheet=123|OwnerPartId=-1|Location.X=1100|Location.Y=830|CurrentPartId=1|LibraryPath=*|SourceLibraryName=FPGA_CONN.SchLib|TargetFileName=*|AreaColor=11599871|Color=128|PartIDLocked=T|NotUseDBTableName=T|DesignItemId=M3 screw
|RECORD=12|OwnerIndex=1008|IsNotAccesible=T|OwnerPartId=1|Location.X=1100|Location.Y=830|Radius=9|Radius_Frac=18136|LineWidth=1|EndAngle=360.000|Color=16711680
|RECORD=41|OwnerIndex=1008|IndexInSheet=1|OwnerPartId=-1|Location.X=1090|Location.X_Frac=81864|Location.Y=845|Color=8388608|FontID=1|IsHidden=T|Text=Digi-Key|Name=Supplier 1|ReadOnlyState=3
|RECORD=41|OwnerIndex=1008|IndexInSheet=2|OwnerPartId=-1|Location.X=1090|Location.X_Frac=81864|Location.Y=800|Location.Y_Frac=81864|Color=8388608|FontID=1|Text=335-1156-ND|Name=Supplier Part Number 1|ReadOnlyState=3
|RECORD=34|OwnerIndex=1008|IndexInSheet=-1|OwnerPartId=-1|Location.X=1090|Location.X_Frac=81864|Location.Y=839|Location.Y_Frac=18136|Color=8388608|FontID=1|Text=J18|Name=Designator|ReadOnlyState=1
|RECORD=41|OwnerIndex=1008|IndexInSheet=-1|OwnerPartId=-1|Location.X=1090|Location.X_Frac=81864|Location.Y=810|Location.Y_Frac=81864|Color=8388608|FontID=1|Text=M3 screw|Name=Comment
|RECORD=44|OwnerIndex=1008
|RECORD=1|LibReference=M3 screw|PartCount=2|DisplayModeCount=1|IndexInSheet=124|OwnerPartId=-1|Location.X=870|Location.Y=640|CurrentPartId=1|LibraryPath=*|SourceLibraryName=FPGA_CONN.SchLib|TargetFileName=*|AreaColor=11599871|Color=128|PartIDLocked=T|NotUseDBTableName=T|DesignItemId=M3 screw
|RECORD=12|OwnerIndex=1015|IsNotAccesible=T|OwnerPartId=1|Location.X=870|Location.Y=640|Radius=9|Radius_Frac=18136|LineWidth=1|EndAngle=360.000|Color=16711680
|RECORD=41|OwnerIndex=1015|IndexInSheet=1|OwnerPartId=-1|Location.X=860|Location.X_Frac=81864|Location.Y=655|Color=8388608|FontID=1|IsHidden=T|Text=Digi-Key|Name=Supplier 1|ReadOnlyState=3
|RECORD=41|OwnerIndex=1015|IndexInSheet=2|OwnerPartId=-1|Location.X=860|Location.X_Frac=81864|Location.Y=610|Location.Y_Frac=81864|Color=8388608|FontID=1|Text=335-1156-ND|Name=Supplier Part Number 1|ReadOnlyState=3
|RECORD=34|OwnerIndex=1015|IndexInSheet=-1|OwnerPartId=-1|Location.X=860|Location.X_Frac=81864|Location.Y=649|Location.Y_Frac=18136|Color=8388608|FontID=1|Text=J19|Name=Designator|ReadOnlyState=1
|RECORD=41|OwnerIndex=1015|IndexInSheet=-1|OwnerPartId=-1|Location.X=860|Location.X_Frac=81864|Location.Y=620|Location.Y_Frac=81864|Color=8388608|FontID=1|Text=M3 screw|Name=Comment
|RECORD=44|OwnerIndex=1015
|RECORD=1|LibReference=M3 screw|PartCount=2|DisplayModeCount=1|IndexInSheet=125|OwnerPartId=-1|Location.X=870|Location.Y=590|CurrentPartId=1|LibraryPath=*|SourceLibraryName=FPGA_CONN.SchLib|TargetFileName=*|AreaColor=11599871|Color=128|PartIDLocked=T|NotUseDBTableName=T|DesignItemId=M3 screw
|RECORD=12|OwnerIndex=1022|IsNotAccesible=T|OwnerPartId=1|Location.X=870|Location.Y=590|Radius=9|Radius_Frac=18136|LineWidth=1|EndAngle=360.000|Color=16711680
|RECORD=41|OwnerIndex=1022|IndexInSheet=1|OwnerPartId=-1|Location.X=860|Location.X_Frac=81864|Location.Y=605|Color=8388608|FontID=1|IsHidden=T|Text=Digi-Key|Name=Supplier 1|ReadOnlyState=3
|RECORD=41|OwnerIndex=1022|IndexInSheet=2|OwnerPartId=-1|Location.X=860|Location.X_Frac=81864|Location.Y=560|Location.Y_Frac=81864|Color=8388608|FontID=1|Text=335-1156-ND|Name=Supplier Part Number 1|ReadOnlyState=3
|RECORD=34|OwnerIndex=1022|IndexInSheet=-1|OwnerPartId=-1|Location.X=860|Location.X_Frac=81864|Location.Y=599|Location.Y_Frac=18136|Color=8388608|FontID=1|Text=J20|Name=Designator|ReadOnlyState=1
|RECORD=41|OwnerIndex=1022|IndexInSheet=-1|OwnerPartId=-1|Location.X=860|Location.X_Frac=81864|Location.Y=570|Location.Y_Frac=81864|Color=8388608|FontID=1|Text=M3 screw|Name=Comment
|RECORD=44|OwnerIndex=1022
|RECORD=1|LibReference=M3 screw|PartCount=2|DisplayModeCount=1|IndexInSheet=126|OwnerPartId=-1|Location.X=870|Location.Y=540|CurrentPartId=1|LibraryPath=*|SourceLibraryName=FPGA_CONN.SchLib|TargetFileName=*|AreaColor=11599871|Color=128|PartIDLocked=T|NotUseDBTableName=T|DesignItemId=M3 screw
|RECORD=12|OwnerIndex=1029|IsNotAccesible=T|OwnerPartId=1|Location.X=870|Location.Y=540|Radius=9|Radius_Frac=18136|LineWidth=1|EndAngle=360.000|Color=16711680
|RECORD=41|OwnerIndex=1029|IndexInSheet=1|OwnerPartId=-1|Location.X=860|Location.X_Frac=81864|Location.Y=555|Color=8388608|FontID=1|IsHidden=T|Text=Digi-Key|Name=Supplier 1|ReadOnlyState=3
|RECORD=41|OwnerIndex=1029|IndexInSheet=2|OwnerPartId=-1|Location.X=860|Location.X_Frac=81864|Location.Y=510|Location.Y_Frac=81864|Color=8388608|FontID=1|Text=335-1156-ND|Name=Supplier Part Number 1|ReadOnlyState=3
|RECORD=34|OwnerIndex=1029|IndexInSheet=-1|OwnerPartId=-1|Location.X=860|Location.X_Frac=81864|Location.Y=549|Location.Y_Frac=18136|Color=8388608|FontID=1|Text=J21|Name=Designator|ReadOnlyState=1
|RECORD=41|OwnerIndex=1029|IndexInSheet=-1|OwnerPartId=-1|Location.X=860|Location.X_Frac=81864|Location.Y=520|Location.Y_Frac=81864|Color=8388608|FontID=1|Text=M3 screw|Name=Comment
|RECORD=44|OwnerIndex=1029
|RECORD=1|LibReference=M3 screw|PartCount=2|DisplayModeCount=1|IndexInSheet=127|OwnerPartId=-1|Location.X=870|Location.Y=490|CurrentPartId=1|LibraryPath=*|SourceLibraryName=FPGA_CONN.SchLib|TargetFileName=*|AreaColor=11599871|Color=128|PartIDLocked=T|NotUseDBTableName=T|DesignItemId=M3 screw
|RECORD=12|OwnerIndex=1036|IsNotAccesible=T|OwnerPartId=1|Location.X=870|Location.Y=490|Radius=9|Radius_Frac=18136|LineWidth=1|EndAngle=360.000|Color=16711680
|RECORD=41|OwnerIndex=1036|IndexInSheet=1|OwnerPartId=-1|Location.X=860|Location.X_Frac=81864|Location.Y=505|Color=8388608|FontID=1|IsHidden=T|Text=Digi-Key|Name=Supplier 1|ReadOnlyState=3
|RECORD=41|OwnerIndex=1036|IndexInSheet=2|OwnerPartId=-1|Location.X=860|Location.X_Frac=81864|Location.Y=460|Location.Y_Frac=81864|Color=8388608|FontID=1|Text=335-1156-ND|Name=Supplier Part Number 1|ReadOnlyState=3
|RECORD=34|OwnerIndex=1036|IndexInSheet=-1|OwnerPartId=-1|Location.X=860|Location.X_Frac=81864|Location.Y=499|Location.Y_Frac=18136|Color=8388608|FontID=1|Text=J22|Name=Designator|ReadOnlyState=1
|RECORD=41|OwnerIndex=1036|IndexInSheet=-1|OwnerPartId=-1|Location.X=860|Location.X_Frac=81864|Location.Y=470|Location.Y_Frac=81864|Color=8388608|FontID=1|Text=M3 screw|Name=Comment
|RECORD=44|OwnerIndex=1036
|RECORD=1|LibReference=M3 screw|PartCount=2|DisplayModeCount=1|IndexInSheet=128|OwnerPartId=-1|Location.X=1160|Location.Y=980|CurrentPartId=1|LibraryPath=*|SourceLibraryName=FPGA_CONN.SchLib|TargetFileName=*|AreaColor=11599871|Color=128|PartIDLocked=T|NotUseDBTableName=T|DesignItemId=M3 screw
|RECORD=12|OwnerIndex=1043|IsNotAccesible=T|OwnerPartId=1|Location.X=1160|Location.Y=980|Radius=9|Radius_Frac=18136|LineWidth=1|EndAngle=360.000|Color=16711680
|RECORD=41|OwnerIndex=1043|IndexInSheet=1|OwnerPartId=-1|Location.X=1150|Location.X_Frac=81864|Location.Y=995|Color=8388608|FontID=1|IsHidden=T|Text=Digi-Key|Name=Supplier 1|ReadOnlyState=3
|RECORD=41|OwnerIndex=1043|IndexInSheet=2|OwnerPartId=-1|Location.X=1150|Location.X_Frac=81864|Location.Y=950|Location.Y_Frac=81864|Color=8388608|FontID=1|Text=335-1156-ND|Name=Supplier Part Number 1|ReadOnlyState=3
|RECORD=34|OwnerIndex=1043|IndexInSheet=-1|OwnerPartId=-1|Location.X=1150|Location.X_Frac=81864|Location.Y=989|Location.Y_Frac=18136|Color=8388608|FontID=1|Text=J23|Name=Designator|ReadOnlyState=1
|RECORD=41|OwnerIndex=1043|IndexInSheet=-1|OwnerPartId=-1|Location.X=1150|Location.X_Frac=81864|Location.Y=960|Location.Y_Frac=81864|Color=8388608|FontID=1|Text=M3 screw|Name=Comment
|RECORD=44|OwnerIndex=1043
|RECORD=1|LibReference=M3 screw|PartCount=2|DisplayModeCount=1|IndexInSheet=129|OwnerPartId=-1|Location.X=1160|Location.Y=930|CurrentPartId=1|LibraryPath=*|SourceLibraryName=FPGA_CONN.SchLib|TargetFileName=*|AreaColor=11599871|Color=128|PartIDLocked=T|NotUseDBTableName=T|DesignItemId=M3 screw
|RECORD=12|OwnerIndex=1050|IsNotAccesible=T|OwnerPartId=1|Location.X=1160|Location.Y=930|Radius=9|Radius_Frac=18136|LineWidth=1|EndAngle=360.000|Color=16711680
|RECORD=41|OwnerIndex=1050|IndexInSheet=1|OwnerPartId=-1|Location.X=1150|Location.X_Frac=81864|Location.Y=945|Color=8388608|FontID=1|IsHidden=T|Text=Digi-Key|Name=Supplier 1|ReadOnlyState=3
|RECORD=41|OwnerIndex=1050|IndexInSheet=2|OwnerPartId=-1|Location.X=1150|Location.X_Frac=81864|Location.Y=900|Location.Y_Frac=81864|Color=8388608|FontID=1|Text=335-1156-ND|Name=Supplier Part Number 1|ReadOnlyState=3
|RECORD=34|OwnerIndex=1050|IndexInSheet=-1|OwnerPartId=-1|Location.X=1150|Location.X_Frac=81864|Location.Y=939|Location.Y_Frac=18136|Color=8388608|FontID=1|Text=J24|Name=Designator|ReadOnlyState=1
|RECORD=41|OwnerIndex=1050|IndexInSheet=-1|OwnerPartId=-1|Location.X=1150|Location.X_Frac=81864|Location.Y=910|Location.Y_Frac=81864|Color=8388608|FontID=1|Text=M3 screw|Name=Comment
|RECORD=44|OwnerIndex=1050
|RECORD=1|LibReference=M3 screw|PartCount=2|DisplayModeCount=1|IndexInSheet=130|OwnerPartId=-1|Location.X=1160|Location.Y=880|CurrentPartId=1|LibraryPath=*|SourceLibraryName=FPGA_CONN.SchLib|TargetFileName=*|AreaColor=11599871|Color=128|PartIDLocked=T|NotUseDBTableName=T|DesignItemId=M3 screw
|RECORD=12|OwnerIndex=1057|IsNotAccesible=T|OwnerPartId=1|Location.X=1160|Location.Y=880|Radius=9|Radius_Frac=18136|LineWidth=1|EndAngle=360.000|Color=16711680
|RECORD=41|OwnerIndex=1057|IndexInSheet=1|OwnerPartId=-1|Location.X=1150|Location.X_Frac=81864|Location.Y=895|Color=8388608|FontID=1|IsHidden=T|Text=Digi-Key|Name=Supplier 1|ReadOnlyState=3
|RECORD=41|OwnerIndex=1057|IndexInSheet=2|OwnerPartId=-1|Location.X=1150|Location.X_Frac=81864|Location.Y=850|Location.Y_Frac=81864|Color=8388608|FontID=1|Text=335-1156-ND|Name=Supplier Part Number 1|ReadOnlyState=3
|RECORD=34|OwnerIndex=1057|IndexInSheet=-1|OwnerPartId=-1|Location.X=1150|Location.X_Frac=81864|Location.Y=889|Location.Y_Frac=18136|Color=8388608|FontID=1|Text=J25|Name=Designator|ReadOnlyState=1
|RECORD=41|OwnerIndex=1057|IndexInSheet=-1|OwnerPartId=-1|Location.X=1150|Location.X_Frac=81864|Location.Y=860|Location.Y_Frac=81864|Color=8388608|FontID=1|Text=M3 screw|Name=Comment
|RECORD=44|OwnerIndex=1057
|RECORD=1|LibReference=M3 screw|PartCount=2|DisplayModeCount=1|IndexInSheet=131|OwnerPartId=-1|Location.X=1160|Location.Y=830|CurrentPartId=1|LibraryPath=*|SourceLibraryName=FPGA_CONN.SchLib|TargetFileName=*|AreaColor=11599871|Color=128|PartIDLocked=T|NotUseDBTableName=T|DesignItemId=M3 screw
|RECORD=12|OwnerIndex=1064|IsNotAccesible=T|OwnerPartId=1|Location.X=1160|Location.Y=830|Radius=9|Radius_Frac=18136|LineWidth=1|EndAngle=360.000|Color=16711680
|RECORD=41|OwnerIndex=1064|IndexInSheet=1|OwnerPartId=-1|Location.X=1150|Location.X_Frac=81864|Location.Y=845|Color=8388608|FontID=1|IsHidden=T|Text=Digi-Key|Name=Supplier 1|ReadOnlyState=3
|RECORD=41|OwnerIndex=1064|IndexInSheet=2|OwnerPartId=-1|Location.X=1150|Location.X_Frac=81864|Location.Y=800|Location.Y_Frac=81864|Color=8388608|FontID=1|Text=335-1156-ND|Name=Supplier Part Number 1|ReadOnlyState=3
|RECORD=34|OwnerIndex=1064|IndexInSheet=-1|OwnerPartId=-1|Location.X=1150|Location.X_Frac=81864|Location.Y=839|Location.Y_Frac=18136|Color=8388608|FontID=1|Text=J26|Name=Designator|ReadOnlyState=1
|RECORD=41|OwnerIndex=1064|IndexInSheet=-1|OwnerPartId=-1|Location.X=1150|Location.X_Frac=81864|Location.Y=810|Location.Y_Frac=81864|Color=8388608|FontID=1|Text=M3 screw|Name=Comment
|RECORD=44|OwnerIndex=1064
|RECORD=1|LibReference=M3 screw|PartCount=2|DisplayModeCount=1|IndexInSheet=132|OwnerPartId=-1|Location.X=940|Location.Y=640|CurrentPartId=1|LibraryPath=*|SourceLibraryName=FPGA_CONN.SchLib|TargetFileName=*|AreaColor=11599871|Color=128|PartIDLocked=T|NotUseDBTableName=T|DesignItemId=M3 screw
|RECORD=12|OwnerIndex=1071|IsNotAccesible=T|OwnerPartId=1|Location.X=940|Location.Y=640|Radius=9|Radius_Frac=18136|LineWidth=1|EndAngle=360.000|Color=16711680
|RECORD=41|OwnerIndex=1071|IndexInSheet=1|OwnerPartId=-1|Location.X=930|Location.X_Frac=81864|Location.Y=655|Color=8388608|FontID=1|IsHidden=T|Text=Digi-Key|Name=Supplier 1|ReadOnlyState=3
|RECORD=41|OwnerIndex=1071|IndexInSheet=2|OwnerPartId=-1|Location.X=930|Location.X_Frac=81864|Location.Y=610|Location.Y_Frac=81864|Color=8388608|FontID=1|Text=335-1156-ND|Name=Supplier Part Number 1|ReadOnlyState=3
|RECORD=34|OwnerIndex=1071|IndexInSheet=-1|OwnerPartId=-1|Location.X=930|Location.X_Frac=81864|Location.Y=649|Location.Y_Frac=18136|Color=8388608|FontID=1|Text=J27|Name=Designator|ReadOnlyState=1
|RECORD=41|OwnerIndex=1071|IndexInSheet=-1|OwnerPartId=-1|Location.X=930|Location.X_Frac=81864|Location.Y=620|Location.Y_Frac=81864|Color=8388608|FontID=1|Text=M3 screw|Name=Comment
|RECORD=44|OwnerIndex=1071
|RECORD=1|LibReference=M3 screw|PartCount=2|DisplayModeCount=1|IndexInSheet=133|OwnerPartId=-1|Location.X=940|Location.Y=590|CurrentPartId=1|LibraryPath=*|SourceLibraryName=FPGA_CONN.SchLib|TargetFileName=*|AreaColor=11599871|Color=128|PartIDLocked=T|NotUseDBTableName=T|DesignItemId=M3 screw
|RECORD=12|OwnerIndex=1078|IsNotAccesible=T|OwnerPartId=1|Location.X=940|Location.Y=590|Radius=9|Radius_Frac=18136|LineWidth=1|EndAngle=360.000|Color=16711680
|RECORD=41|OwnerIndex=1078|IndexInSheet=1|OwnerPartId=-1|Location.X=930|Location.X_Frac=81864|Location.Y=605|Color=8388608|FontID=1|IsHidden=T|Text=Digi-Key|Name=Supplier 1|ReadOnlyState=3
|RECORD=41|OwnerIndex=1078|IndexInSheet=2|OwnerPartId=-1|Location.X=930|Location.X_Frac=81864|Location.Y=560|Location.Y_Frac=81864|Color=8388608|FontID=1|Text=335-1156-ND|Name=Supplier Part Number 1|ReadOnlyState=3
|RECORD=34|OwnerIndex=1078|IndexInSheet=-1|OwnerPartId=-1|Location.X=930|Location.X_Frac=81864|Location.Y=599|Location.Y_Frac=18136|Color=8388608|FontID=1|Text=J28|Name=Designator|ReadOnlyState=1
|RECORD=41|OwnerIndex=1078|IndexInSheet=-1|OwnerPartId=-1|Location.X=930|Location.X_Frac=81864|Location.Y=570|Location.Y_Frac=81864|Color=8388608|FontID=1|Text=M3 screw|Name=Comment
|RECORD=44|OwnerIndex=1078
|RECORD=1|LibReference=M3 screw|PartCount=2|DisplayModeCount=1|IndexInSheet=134|OwnerPartId=-1|Location.X=940|Location.Y=540|CurrentPartId=1|LibraryPath=*|SourceLibraryName=FPGA_CONN.SchLib|TargetFileName=*|AreaColor=11599871|Color=128|PartIDLocked=T|NotUseDBTableName=T|DesignItemId=M3 screw
|RECORD=12|OwnerIndex=1085|IsNotAccesible=T|OwnerPartId=1|Location.X=940|Location.Y=540|Radius=9|Radius_Frac=18136|LineWidth=1|EndAngle=360.000|Color=16711680
|RECORD=41|OwnerIndex=1085|IndexInSheet=1|OwnerPartId=-1|Location.X=930|Location.X_Frac=81864|Location.Y=555|Color=8388608|FontID=1|IsHidden=T|Text=Digi-Key|Name=Supplier 1|ReadOnlyState=3
|RECORD=41|OwnerIndex=1085|IndexInSheet=2|OwnerPartId=-1|Location.X=930|Location.X_Frac=81864|Location.Y=510|Location.Y_Frac=81864|Color=8388608|FontID=1|Text=335-1156-ND|Name=Supplier Part Number 1|ReadOnlyState=3
|RECORD=34|OwnerIndex=1085|IndexInSheet=-1|OwnerPartId=-1|Location.X=930|Location.X_Frac=81864|Location.Y=549|Location.Y_Frac=18136|Color=8388608|FontID=1|Text=J29|Name=Designator|ReadOnlyState=1
|RECORD=41|OwnerIndex=1085|IndexInSheet=-1|OwnerPartId=-1|Location.X=930|Location.X_Frac=81864|Location.Y=520|Location.Y_Frac=81864|Color=8388608|FontID=1|Text=M3 screw|Name=Comment
|RECORD=44|OwnerIndex=1085
|RECORD=1|LibReference=M3 screw|PartCount=2|DisplayModeCount=1|IndexInSheet=135|OwnerPartId=-1|Location.X=940|Location.Y=490|CurrentPartId=1|LibraryPath=*|SourceLibraryName=FPGA_CONN.SchLib|TargetFileName=*|AreaColor=11599871|Color=128|PartIDLocked=T|NotUseDBTableName=T|DesignItemId=M3 screw
|RECORD=12|OwnerIndex=1092|IsNotAccesible=T|OwnerPartId=1|Location.X=940|Location.Y=490|Radius=9|Radius_Frac=18136|LineWidth=1|EndAngle=360.000|Color=16711680
|RECORD=41|OwnerIndex=1092|IndexInSheet=1|OwnerPartId=-1|Location.X=930|Location.X_Frac=81864|Location.Y=505|Color=8388608|FontID=1|IsHidden=T|Text=Digi-Key|Name=Supplier 1|ReadOnlyState=3
|RECORD=41|OwnerIndex=1092|IndexInSheet=2|OwnerPartId=-1|Location.X=930|Location.X_Frac=81864|Location.Y=460|Location.Y_Frac=81864|Color=8388608|FontID=1|Text=335-1156-ND|Name=Supplier Part Number 1|ReadOnlyState=3
|RECORD=34|OwnerIndex=1092|IndexInSheet=-1|OwnerPartId=-1|Location.X=930|Location.X_Frac=81864|Location.Y=499|Location.Y_Frac=18136|Color=8388608|FontID=1|Text=J30|Name=Designator|ReadOnlyState=1
|RECORD=41|OwnerIndex=1092|IndexInSheet=-1|OwnerPartId=-1|Location.X=930|Location.X_Frac=81864|Location.Y=470|Location.Y_Frac=81864|Color=8388608|FontID=1|Text=M3 screw|Name=Comment
|RECORD=44|OwnerIndex=1092
|RECORD=1|LibReference=M3 screw|PartCount=2|DisplayModeCount=1|IndexInSheet=136|OwnerPartId=-1|Location.X=1270|Location.Y=990|CurrentPartId=1|LibraryPath=*|SourceLibraryName=FPGA_CONN.SchLib|TargetFileName=*|AreaColor=11599871|Color=128|PartIDLocked=T|NotUseDBTableName=T|DesignItemId=M3 screw
|RECORD=12|OwnerIndex=1099|IsNotAccesible=T|OwnerPartId=1|Location.X=1270|Location.Y=990|Radius=9|Radius_Frac=18136|LineWidth=1|EndAngle=360.000|Color=16711680
|RECORD=41|OwnerIndex=1099|IndexInSheet=1|OwnerPartId=-1|Location.X=1260|Location.X_Frac=81864|Location.Y=1005|Color=8388608|FontID=1|IsHidden=T|Text=Digi-Key|Name=Supplier 1|ReadOnlyState=3
|RECORD=41|OwnerIndex=1099|IndexInSheet=2|OwnerPartId=-1|Location.X=1260|Location.X_Frac=81864|Location.Y=960|Location.Y_Frac=81864|Color=8388608|FontID=1|Text=335-1156-ND|Name=Supplier Part Number 1|ReadOnlyState=3
|RECORD=34|OwnerIndex=1099|IndexInSheet=-1|OwnerPartId=-1|Location.X=1260|Location.X_Frac=81864|Location.Y=999|Location.Y_Frac=18136|Color=8388608|FontID=1|Text=J32|Name=Designator|ReadOnlyState=1
|RECORD=41|OwnerIndex=1099|IndexInSheet=-1|OwnerPartId=-1|Location.X=1260|Location.X_Frac=81864|Location.Y=970|Location.Y_Frac=81864|Color=8388608|FontID=1|Text=M3 screw|Name=Comment
|RECORD=44|OwnerIndex=1099
|RECORD=1|LibReference=M3 screw|PartCount=2|DisplayModeCount=1|IndexInSheet=137|OwnerPartId=-1|Location.X=1330|Location.Y=990|CurrentPartId=1|LibraryPath=*|SourceLibraryName=FPGA_CONN.SchLib|TargetFileName=*|AreaColor=11599871|Color=128|PartIDLocked=T|NotUseDBTableName=T|DesignItemId=M3 screw
|RECORD=12|OwnerIndex=1106|IsNotAccesible=T|OwnerPartId=1|Location.X=1330|Location.Y=990|Radius=9|Radius_Frac=18136|LineWidth=1|EndAngle=360.000|Color=16711680
|RECORD=41|OwnerIndex=1106|IndexInSheet=1|OwnerPartId=-1|Location.X=1320|Location.X_Frac=81864|Location.Y=1005|Color=8388608|FontID=1|IsHidden=T|Text=Digi-Key|Name=Supplier 1|ReadOnlyState=3
|RECORD=41|OwnerIndex=1106|IndexInSheet=2|OwnerPartId=-1|Location.X=1320|Location.X_Frac=81864|Location.Y=960|Location.Y_Frac=81864|Color=8388608|FontID=1|Text=335-1156-ND|Name=Supplier Part Number 1|ReadOnlyState=3
|RECORD=34|OwnerIndex=1106|IndexInSheet=-1|OwnerPartId=-1|Location.X=1320|Location.X_Frac=81864|Location.Y=999|Location.Y_Frac=18136|Color=8388608|FontID=1|Text=J33|Name=Designator|ReadOnlyState=1
|RECORD=41|OwnerIndex=1106|IndexInSheet=-1|OwnerPartId=-1|Location.X=1320|Location.X_Frac=81864|Location.Y=970|Location.Y_Frac=81864|Color=8388608|FontID=1|Text=M3 screw|Name=Comment
|RECORD=44|OwnerIndex=1106
|RECORD=4|IndexInSheet=138|OwnerPartId=-1|Location.X=1260|Location.Y=1020|Color=8388608|FontID=1|Text=PCIe Bracket screws
|RECORD=1|LibReference=SMTC-TSW-105-05-X-S|ComponentDescription=0.025" SQ Post Header, Through-hole, Vertical, -55 to 125 degC, 2.54 mm Pitch, 5-Pin, Male, RoHS|PartCount=2|DisplayModeCount=1|IndexInSheet=139|OwnerPartId=-1|Location.X=460|Location.Y=100|Orientation=1|CurrentPartId=1|LibraryPath=*|SourceLibraryName=Altium Content Vault|TargetFileName=*|AreaColor=11599871|Color=128|PartIDLocked=T|DesignItemId=CMP-1024-00366-1|AllPinCount=5
|RECORD=2|OwnerIndex=1114|OwnerPartId=1|FormalType=1|Electrical=4|PinConglomerate=48|PinLength=20|Location.X=480|Location.Y=150|Name=1|Designator=1|PinPropagationDelay=0.000000E+000
|RECORD=2|OwnerIndex=1114|OwnerPartId=1|FormalType=1|Electrical=4|PinConglomerate=48|PinLength=20|Location.X=480|Location.Y=140|Name=2|Designator=2|PinPropagationDelay=0.000000E+000
|RECORD=2|OwnerIndex=1114|OwnerPartId=1|FormalType=1|Electrical=4|PinConglomerate=48|PinLength=20|Location.X=480|Location.Y=130|Name=3|Designator=3|PinPropagationDelay=0.000000E+000
|RECORD=2|OwnerIndex=1114|OwnerPartId=1|FormalType=1|Electrical=4|PinConglomerate=48|PinLength=20|Location.X=480|Location.Y=120|Name=4|Designator=4|PinPropagationDelay=0.000000E+000
|RECORD=2|OwnerIndex=1114|OwnerPartId=1|FormalType=1|Electrical=4|PinConglomerate=48|PinLength=20|Location.X=480|Location.Y=110|Name=5|Designator=5|PinPropagationDelay=0.000000E+000
|RECORD=6|OwnerIndex=1114|IsNotAccesible=T|IndexInSheet=5|OwnerPartId=1|LineWidth=1|Color=16711680|LocationCount=2|X1=480|Y1=150|X2=473|Y2=150
|RECORD=8|OwnerIndex=1114|IsNotAccesible=T|IndexInSheet=6|OwnerPartId=1|Location.X=470|Location.Y=150|Radius=3|SecondaryRadius=3|LineWidth=1|Color=16711680|AreaColor=16711680|IsSolid=T
|RECORD=6|OwnerIndex=1114|IsNotAccesible=T|IndexInSheet=7|OwnerPartId=1|LineWidth=1|Color=16711680|LocationCount=5|X1=480|Y1=100|X2=460|Y2=100|X3=460|Y3=160|X4=480|Y4=160|X5=480|Y5=100
|RECORD=6|OwnerIndex=1114|IsNotAccesible=T|IndexInSheet=8|OwnerPartId=1|LineWidth=1|Color=16711680|LocationCount=2|X1=480|Y1=140|X2=473|Y2=140
|RECORD=8|OwnerIndex=1114|IsNotAccesible=T|IndexInSheet=9|OwnerPartId=1|Location.X=470|Location.Y=140|Radius=3|SecondaryRadius=3|LineWidth=1|Color=16711680|AreaColor=16711680|IsSolid=T
|RECORD=6|OwnerIndex=1114|IsNotAccesible=T|IndexInSheet=10|OwnerPartId=1|LineWidth=1|Color=16711680|LocationCount=2|X1=480|Y1=130|X2=473|Y2=130
|RECORD=6|OwnerIndex=1114|IsNotAccesible=T|IndexInSheet=11|OwnerPartId=1|LineWidth=1|Color=16711680|LocationCount=2|X1=480|Y1=120|X2=473|Y2=120
|RECORD=8|OwnerIndex=1114|IsNotAccesible=T|IndexInSheet=12|OwnerPartId=1|Location.X=470|Location.Y=130|Radius=3|SecondaryRadius=3|LineWidth=1|Color=16711680|AreaColor=16711680|IsSolid=T
|RECORD=8|OwnerIndex=1114|IsNotAccesible=T|IndexInSheet=13|OwnerPartId=1|Location.X=470|Location.Y=120|Radius=3|SecondaryRadius=3|LineWidth=1|Color=16711680|AreaColor=16711680|IsSolid=T
|RECORD=6|OwnerIndex=1114|IsNotAccesible=T|IndexInSheet=14|OwnerPartId=1|LineWidth=1|Color=16711680|LocationCount=2|X1=480|Y1=110|X2=473|Y2=110
|RECORD=8|OwnerIndex=1114|IsNotAccesible=T|IndexInSheet=15|OwnerPartId=1|Location.X=470|Location.Y=110|Radius=3|SecondaryRadius=3|LineWidth=1|Color=16711680|AreaColor=16711680|IsSolid=T
|RECORD=41|OwnerIndex=1114|IndexInSheet=16|OwnerPartId=-1|Location.X=459|Location.Y=161|Color=8388608|FontID=1|IsHidden=T|Text=DM, 8/1988|Name=PackageVersion
|RECORD=41|OwnerIndex=1114|IndexInSheet=17|OwnerPartId=-1|Location.X=459|Location.Y=161|Color=8388608|FontID=1|IsHidden=T|Text=TSW-105-05-L-S|Name=PartNumber
|RECORD=41|OwnerIndex=1114|IndexInSheet=18|OwnerPartId=-1|Location.X=459|Location.Y=161|Color=8388608|FontID=1|IsHidden=T|Text=Vertical|Name=Orientation
|RECORD=41|OwnerIndex=1114|IndexInSheet=19|OwnerPartId=-1|Location.X=459|Location.Y=161|Color=8388608|FontID=1|IsHidden=T|Text=-55 to 125 degC|Name=Temperature Range
|RECORD=41|OwnerIndex=1114|IndexInSheet=20|OwnerPartId=-1|Location.X=459|Location.Y=161|Color=8388608|FontID=1|IsHidden=T|Text=Manufacturer URL|Name=ComponentLink1Description
|RECORD=41|OwnerIndex=1114|IndexInSheet=21|OwnerPartId=-1|Location.X=459|Location.Y=161|Color=8388608|FontID=1|IsHidden=T|Text=.025[0.64] SQ. Post Terminal Strip Assembly|Name=PackageDescription
|RECORD=41|OwnerIndex=1114|IndexInSheet=22|OwnerPartId=-1|Location.X=459|Location.Y=161|Color=8388608|FontID=1|IsHidden=T|Text=2.54 mm|Name=Pitch
|RECORD=41|OwnerIndex=1114|IndexInSheet=23|OwnerPartId=-1|Location.X=459|Location.Y=161|Color=8388608|FontID=8|IsHidden=T|Text=http://www.samtec.com/documents/webfiles/pdf/TSW_TH.PDF|Name=ComponentLink2URL
|RECORD=41|OwnerIndex=1114|IndexInSheet=24|OwnerPartId=-1|Location.X=459|Location.Y=161|Color=8388608|FontID=1|IsHidden=T|Text=TSW-105-05-X-S|Name=PackageReference
|RECORD=41|OwnerIndex=1114|IndexInSheet=25|OwnerPartId=-1|Location.X=459|Location.Y=161|Color=8388608|FontID=1|IsHidden=T|Text=Datasheet|Name=ComponentLink2Description
|RECORD=41|OwnerIndex=1114|IndexInSheet=26|OwnerPartId=-1|Location.X=459|Location.Y=161|Color=8388608|FontID=1|IsHidden=T|Text=Through-hole|Name=Mounting Technology
|RECORD=41|OwnerIndex=1114|IndexInSheet=27|OwnerPartId=-1|Location.X=459|Location.Y=161|Color=8388608|FontID=1|IsHidden=T|Text=F-214|Name=DatasheetVersion
|RECORD=41|OwnerIndex=1114|IndexInSheet=28|OwnerPartId=-1|Location.X=459|Location.Y=161|Color=8388608|FontID=8|IsHidden=T|Text=http://www.samtec.com|Name=ComponentLink1URL
|RECORD=41|OwnerIndex=1114|IndexInSheet=29|OwnerPartId=-1|Location.X=459|Location.Y=161|Color=8388608|FontID=1|IsHidden=T|Text=True|Name=RoHS
|RECORD=41|OwnerIndex=1114|IndexInSheet=30|OwnerPartId=-1|Location.X=459|Location.Y=161|Color=8388608|FontID=8|IsHidden=T|Text=http://www.samtec.com/documents/webfiles/cpdf/TSW-XXX-XX-XXX-X-XX-XXX-MKT.pdf|Name=ComponentLink3URL
|RECORD=41|OwnerIndex=1114|IndexInSheet=31|OwnerPartId=-1|Location.X=459|Location.Y=161|Color=8388608|FontID=1|IsHidden=T|Text=Package Specification|Name=ComponentLink3Description
|RECORD=41|OwnerIndex=1114|IndexInSheet=32|OwnerPartId=-1|Location.X=459|Location.Y=161|Color=8388608|FontID=1|IsHidden=T|Text=Samtec|Name=Manufacturer
|RECORD=34|OwnerIndex=1114|IndexInSheet=-1|OwnerPartId=-1|Location.X=459|Location.Y=161|Color=8388608|FontID=1|Text=P1|Name=Designator|ReadOnlyState=1
|RECORD=41|OwnerIndex=1114|IndexInSheet=-1|OwnerPartId=-1|Location.X=459|Location.Y=89|Color=8388608|FontID=1|Text=TSW-105-05-L-S|Name=Comment
|RECORD=44|OwnerIndex=1114
|RECORD=45|OwnerIndex=1155|IndexInSheet=-1|Description=.025 SQ Post Terminal Strip Assembly, 1x5 Pins, Vertical, 2.54mm Pitch, Male|UseComponentLibrary=T|ModelName=SMTC-TSW-105-05-X-S|ModelType=PCBLIB|DatafileCount=1|ModelDatafileEntity0=SMTC-TSW-105-05-X-S|ModelDatafileKind0=PCBLib|IsCurrent=T|DatalinksLocked=T|DatabaseDatalinksLocked=T
|RECORD=46|OwnerIndex=1156
|RECORD=48|OwnerIndex=1156
|RECORD=41|OwnerIndex=1158|IndexInSheet=-1|OwnerPartId=-1|Color=8388608|FontID=1|IsHidden=T|Text=2D|Name=Available Preview Images
|RECORD=17|IndexInSheet=140|OwnerPartId=-1|ShowNetName=T|Location.X=580|Location.Y=180|Orientation=1|Color=128|FontID=1|Text=+3.3V
|RECORD=17|IndexInSheet=141|OwnerPartId=-1|Style=4|ShowNetName=T|Location.X=550|Location.Y=70|Orientation=3|Color=128|FontID=1|Text=GND
|RECORD=17|IndexInSheet=142|OwnerPartId=-1|ShowNetName=T|Location.X=570|Location.Y=130|Color=255|FontID=1|Text=SCL|IsCrossSheetConnector=T
|RECORD=17|IndexInSheet=143|OwnerPartId=-1|ShowNetName=T|Location.X=570|Location.Y=120|Color=255|FontID=1|Text=SDA|IsCrossSheetConnector=T
|RECORD=17|IndexInSheet=144|OwnerPartId=-1|Style=1|ShowNetName=T|Location.X=690|Location.Y=100|Color=255|FontID=1|Text=MAC_FREQ_CTRL|IsCrossSheetConnector=T
|RECORD=1|LibReference=RES-2|ComponentDescription=Chip Resistor, 0 Ohm, 0.1 W, -55 to 155 degC, 0402 (1005 Metric), RoHS, Tape and Reel|PartCount=2|DisplayModeCount=1|IndexInSheet=145|OwnerPartId=-1|Location.X=610|Location.Y=100|CurrentPartId=1|LibraryPath=*|SourceLibraryName=Altium Content Vault|TargetFileName=*|AreaColor=11599871|Color=128|PartIDLocked=T|DesignItemId=CMP-2000-07451-1|AllPinCount=2
|RECORD=2|OwnerIndex=1165|OwnerPartId=1|FormalType=1|Electrical=4|PinConglomerate=32|PinLength=10|Location.X=630|Location.Y=100|Name=2|Designator=2|PinPropagationDelay=0.000000E+000
|RECORD=2|OwnerIndex=1165|OwnerPartId=1|FormalType=1|Electrical=4|PinConglomerate=34|PinLength=10|Location.X=610|Location.Y=100|Name=1|Designator=1|PinPropagationDelay=0.000000E+000
|RECORD=6|OwnerIndex=1165|IsNotAccesible=T|IndexInSheet=2|OwnerPartId=1|LineWidth=1|Color=16711680|LocationCount=10|X1=630|Y1=100|X2=626|Y2=100|X3=625|Y3=98|X4=623|Y4=102|X5=621|Y5=98|X6=619|Y6=102|X7=617|Y7=98|X8=615|Y8=102|X9=614|Y9=100|X10=610|Y10=100
|RECORD=41|OwnerIndex=1165|IndexInSheet=3|OwnerPartId=-1|Location.X=598|Location.Y=115|Color=8388608|FontID=1|IsHidden=T|Text=50V|Name=Voltage Rating (DC)
|RECORD=41|OwnerIndex=1165|IndexInSheet=4|OwnerPartId=-1|Location.X=598|Location.Y=115|Color=8388608|FontID=1|IsHidden=T|Text=2|Name=Number of Terminations
|RECORD=41|OwnerIndex=1165|IndexInSheet=5|OwnerPartId=-1|Location.X=598|Location.Y=115|Color=8388608|FontID=1|IsHidden=T|Text=SurfaceMount|Name=Mount
|RECORD=41|OwnerIndex=1165|IndexInSheet=6|OwnerPartId=-1|Location.X=598|Location.Y=115|Color=8388608|FontID=1|IsHidden=T|Text=0.35mm|Name=Height
|RECORD=41|OwnerIndex=1165|IndexInSheet=7|OwnerPartId=-1|Location.X=598|Location.Y=115|Color=8388608|FontID=1|IsHidden=T|Text=TapeandReel|Name=Packaging
|RECORD=41|OwnerIndex=1165|IndexInSheet=8|OwnerPartId=-1|Location.X=598|Location.Y=115|Color=8388608|FontID=1|IsHidden=T|Text=Tin|Name=Contact Plating
|RECORD=41|OwnerIndex=1165|IndexInSheet=9|OwnerPartId=-1|Location.X=598|Location.Y=115|Color=8388608|FontID=8|IsHidden=T|Text=http://www.panasonic.com/|Name=Manufacturer URL
|RECORD=41|OwnerIndex=1165|IndexInSheet=10|OwnerPartId=-1|Location.X=598|Location.Y=115|Color=8388608|FontID=1|IsHidden=T|Text=ThickFilm|Name=Composition
|RECORD=41|OwnerIndex=1165|IndexInSheet=11|OwnerPartId=-1|Location.X=598|Location.Y=115|Color=8388608|FontID=1|IsHidden=T|Text=155degC|Name=Max Operating Temperature
|RECORD=41|OwnerIndex=1165|IndexInSheet=12|OwnerPartId=-1|Location.X=598|Location.Y=115|Color=8388608|FontID=1|IsHidden=T|Text=600ppm/??C|Name=Temperature Coefficient
|RECORD=41|OwnerIndex=1165|IndexInSheet=13|OwnerPartId=-1|Location.X=598|Location.Y=115|Color=8388608|FontID=1|IsHidden=T|Text=NoSVHC|Name=REACH SVHC
|RECORD=41|OwnerIndex=1165|IndexInSheet=14|OwnerPartId=-1|Location.X=598|Location.Y=115|Color=8388608|FontID=1|IsHidden=T|Text=0402|Name=Case/Package
|RECORD=41|OwnerIndex=1165|IndexInSheet=15|OwnerPartId=-1|Location.X=598|Location.Y=115|Color=8388608|FontID=1|IsHidden=T|Text=100mW|Name=Max Power Dissipation
|RECORD=41|OwnerIndex=1165|IndexInSheet=16|OwnerPartId=-1|Location.X=598|Location.Y=115|Color=8388608|FontID=1|IsHidden=T|Text=402|Name=Package Reference
|RECORD=41|OwnerIndex=1165|IndexInSheet=17|OwnerPartId=-1|Location.X=598|Location.Y=115|Color=8388608|FontID=1|IsHidden=T|Text=0.5mm|Name=Depth
|RECORD=41|OwnerIndex=1165|IndexInSheet=18|OwnerPartId=-1|Location.X=598|Location.Y=115|Color=8388608|FontID=1|IsHidden=T|Text=Panasonic|Name=Manufacturer
|RECORD=41|OwnerIndex=1165|IndexInSheet=19|OwnerPartId=-1|Location.X=598|Location.Y=115|Color=8388608|FontID=1|IsHidden=T|Text=2-Pin Surface Mount Device, Body 1 x 0.5 mm|Name=Package Description
|RECORD=41|OwnerIndex=1165|IndexInSheet=20|OwnerPartId=-1|Location.X=598|Location.Y=115|Color=8388608|FontID=8|IsHidden=T|Text=https://industrial.panasonic.com/cdbs/www-data/pdf/RDA0000/AOA0000C301.pdf|Name=Datasheet URL
|RECORD=41|OwnerIndex=1165|IndexInSheet=21|OwnerPartId=-1|Location.X=598|Location.Y=115|Color=8388608|FontID=1|IsHidden=T|Text=True|Name=RoHSCompliant
|RECORD=41|OwnerIndex=1165|IndexInSheet=22|OwnerPartId=-1|Location.X=598|Location.Y=115|Color=8388608|FontID=1|IsHidden=T|Text=0402|Name=Case Code (Imperial)
|RECORD=41|OwnerIndex=1165|IndexInSheet=23|OwnerPartId=-1|Location.X=598|Location.Y=115|Color=8388608|FontID=1|IsHidden=T|Text=0mOhm|Name=Resistance
|RECORD=41|OwnerIndex=1165|IndexInSheet=24|OwnerPartId=-1|Location.X=598|Location.Y=115|Color=8388608|FontID=1|IsHidden=T|Text=Not|Name=Military Standard
|RECORD=41|OwnerIndex=1165|IndexInSheet=25|OwnerPartId=-1|Location.X=598|Location.Y=115|Color=8388608|FontID=1|IsHidden=T|Text=5%|Name=Tolerance
|RECORD=41|OwnerIndex=1165|IndexInSheet=26|OwnerPartId=-1|Location.X=598|Location.Y=115|Color=8388608|FontID=1|IsHidden=T|Text=-55degC|Name=Min Operating Temperature
|RECORD=41|OwnerIndex=1165|IndexInSheet=27|OwnerPartId=-1|Location.X=598|Location.Y=115|Color=8388608|FontID=1|IsHidden=T|Text=100mW|Name=Power Rating
|RECORD=41|OwnerIndex=1165|IndexInSheet=28|OwnerPartId=-1|Location.X=598|Location.Y=115|Color=8388608|FontID=1|IsHidden=T|Text=03/2015|Name=Datasheet Version
|RECORD=41|OwnerIndex=1165|IndexInSheet=29|OwnerPartId=-1|Location.X=598|Location.Y=115|Color=8388608|FontID=1|IsHidden=T|Text=1mm|Name=Length
|RECORD=41|OwnerIndex=1165|IndexInSheet=30|OwnerPartId=-1|Location.X=598|Location.Y=115|Color=8388608|FontID=1|IsHidden=T|Text=1005|Name=Case Code (Metric)
|RECORD=41|OwnerIndex=1165|IndexInSheet=31|OwnerPartId=-1|Location.X=598|Location.Y=115|Color=8388608|FontID=1|IsHidden=T|Text=SMD/SMT|Name=Termination
|RECORD=41|OwnerIndex=1165|IndexInSheet=32|OwnerPartId=-1|Location.X=598|Location.Y=115|Color=8388608|FontID=1|IsHidden=T|Text=SurfaceMount|Name=Mounting Technology
|RECORD=41|OwnerIndex=1165|IndexInSheet=33|OwnerPartId=-1|Location.X=598|Location.Y=115|Color=8388608|FontID=1|IsHidden=T|Text=50V|Name=Voltage Rating
|RECORD=41|OwnerIndex=1165|IndexInSheet=34|OwnerPartId=-1|Location.X=598|Location.Y=115|Color=8388608|FontID=1|IsHidden=T|Text=0.02inch|Name=Width
|RECORD=41|OwnerIndex=1165|IndexInSheet=35|OwnerPartId=-1|Location.X=598|Location.Y=115|Color=8388608|FontID=1|IsHidden=T|Text=1|Name=Package Quantity
|RECORD=41|OwnerIndex=1165|IndexInSheet=36|OwnerPartId=-1|Location.X=598|Location.Y=115|Color=8388608|FontID=1|IsHidden=T|Text=LeadFree|Name=Lead Free
|RECORD=41|OwnerIndex=1165|IndexInSheet=37|OwnerPartId=-1|Location.X=598|Location.Y=115|Color=8388608|FontID=1|IsHidden=T|Text=No|Name=Radiation Hardening
|RECORD=34|OwnerIndex=1165|IndexInSheet=-1|OwnerPartId=-1|Location.X=590|Location.Y=100|Color=8388608|FontID=1|Text=R48|Name=Designator|ReadOnlyState=1
|RECORD=41|OwnerIndex=1165|IndexInSheet=-1|OwnerPartId=-1|Location.X=630|Location.Y=100|Color=8388608|FontID=1|Text=0_1%_0402|Name=Comment
|RECORD=44|OwnerIndex=1165
|RECORD=45|OwnerIndex=1208|IndexInSheet=-1|Description=Chip Resistor, 2-Leads, Body 1.05x0.55mm, IPC High Density|UseComponentLibrary=T|ModelName=RESC1005X40X25LL05T05|ModelType=PCBLIB|DatafileCount=1|ModelDatafileEntity0=RESC1005X40X25LL05T05|ModelDatafileKind0=PCBLib|IsCurrent=T|DatalinksLocked=T|DatabaseDatalinksLocked=T
|RECORD=46|OwnerIndex=1209
|RECORD=48|OwnerIndex=1209
|RECORD=41|OwnerIndex=1211|IndexInSheet=-1|OwnerPartId=-1|Color=8388608|FontID=1|IsHidden=T|Text=2D|Name=Available Preview Images
|RECORD=45|OwnerIndex=1208|IndexInSheet=-1|Description=Chip Resistor, 2-Leads, Body 1.05x0.55mm, IPC Low Density|UseComponentLibrary=T|ModelName=RESC1005X40X25ML05T05|ModelType=PCBLIB|DatafileCount=1|ModelDatafileEntity0=RESC1005X40X25ML05T05|ModelDatafileKind0=PCBLib|DatalinksLocked=T|DatabaseDatalinksLocked=T
|RECORD=46|OwnerIndex=1213
|RECORD=48|OwnerIndex=1213
|RECORD=41|OwnerIndex=1215|IndexInSheet=-1|OwnerPartId=-1|Color=8388608|FontID=1|IsHidden=T|Text=2D|Name=Available Preview Images
|RECORD=45|OwnerIndex=1208|IndexInSheet=-1|Description=Chip Resistor, 2-Leads, Body 1.05x0.55mm, IPC Medium Density|UseComponentLibrary=T|ModelName=RESC1005X40X25NL05T05|ModelType=PCBLIB|DatafileCount=1|ModelDatafileEntity0=RESC1005X40X25NL05T05|ModelDatafileKind0=PCBLib|DatalinksLocked=T|DatabaseDatalinksLocked=T
|RECORD=46|OwnerIndex=1217
|RECORD=48|OwnerIndex=1217
|RECORD=41|OwnerIndex=1219|IndexInSheet=-1|OwnerPartId=-1|Color=8388608|FontID=1|IsHidden=T|Text=2D|Name=Available Preview Images
|RECORD=4|IndexInSheet=146|OwnerPartId=-1|Location.X=800|Location.Y=90|Color=8388608|FontID=1|Text=Allow DAC daughter card to control atomic clock analog input
|RECORD=1|LibReference=GNSS Header 16-pin|PartCount=2|DisplayModeCount=1|IndexInSheet=147|OwnerPartId=-1|Location.X=580|Location.Y=950|CurrentPartId=1|LibraryPath=*|SourceLibraryName=FPGA_CONN.SchLib|TargetFileName=*|AreaColor=11599871|Color=128|PartIDLocked=T|DesignItemId=GNSS Header 16-pin|AllPinCount=16
|RECORD=41|OwnerIndex=1222|OwnerPartId=-1|Location.X=548|Location.Y=1040|Color=8388608|FontID=1|IsHidden=T|Text=Digi-Key|Name=Supplier 1|ReadOnlyState=3
|RECORD=14|OwnerIndex=1222|IsNotAccesible=T|IndexInSheet=1|OwnerPartId=1|Location.X=580|Location.Y=940|Corner.X=630|Corner.Y=1040|Color=128|AreaColor=11599871|IsSolid=T
|RECORD=2|OwnerIndex=1222|OwnerPartId=1|FormalType=1|Electrical=4|PinConglomerate=58|PinLength=30|Location.X=580|Location.Y=1030|Name=1|Designator=1|SwapIDPart=Ž&Ž||PinPropagationDelay=0.000000E+000
|RECORD=2|OwnerIndex=1222|OwnerPartId=1|FormalType=1|Electrical=4|PinConglomerate=58|PinLength=30|Location.X=580|Location.Y=1020|Name=2|Designator=2|SwapIDPart=Ž&Ž||PinPropagationDelay=0.000000E+000
|RECORD=2|OwnerIndex=1222|OwnerPartId=1|FormalType=1|Electrical=4|PinConglomerate=58|PinLength=30|Location.X=580|Location.Y=1010|Name=3|Designator=3|SwapIDPart=Ž&Ž||PinPropagationDelay=0.000000E+000
|RECORD=2|OwnerIndex=1222|OwnerPartId=1|FormalType=1|Electrical=4|PinConglomerate=58|PinLength=30|Location.X=580|Location.Y=1000|Name=4|Designator=4|SwapIDPart=Ž&Ž||PinPropagationDelay=0.000000E+000
|RECORD=2|OwnerIndex=1222|OwnerPartId=1|FormalType=1|Electrical=4|PinConglomerate=56|PinLength=30|Location.X=630|Location.Y=1030|Name=5|Designator=5|SwapIDPart=Ž&Ž||PinPropagationDelay=0.000000E+000
|RECORD=2|OwnerIndex=1222|OwnerPartId=1|FormalType=1|Electrical=4|PinConglomerate=56|PinLength=30|Location.X=630|Location.Y=1020|Name=6|Designator=6|SwapIDPart=Ž&Ž||PinPropagationDelay=0.000000E+000
|RECORD=2|OwnerIndex=1222|OwnerPartId=1|FormalType=1|Electrical=4|PinConglomerate=56|PinLength=30|Location.X=630|Location.Y=1010|Name=7|Designator=7|SwapIDPart=Ž&Ž||PinPropagationDelay=0.000000E+000
|RECORD=2|OwnerIndex=1222|OwnerPartId=1|FormalType=1|Electrical=4|PinConglomerate=56|PinLength=30|Location.X=630|Location.Y=1000|Name=8|Designator=8|SwapIDPart=Ž&Ž||PinPropagationDelay=0.000000E+000
|RECORD=2|OwnerIndex=1222|OwnerPartId=1|FormalType=1|Electrical=4|PinConglomerate=58|PinLength=30|Location.X=580|Location.Y=980|Name=9|Designator=9|SwapIDPart=Ž&Ž||PinPropagationDelay=0.000000E+000
|RECORD=2|OwnerIndex=1222|OwnerPartId=1|FormalType=1|Electrical=4|PinConglomerate=58|PinLength=30|Location.X=580|Location.Y=970|Name=10|Designator=10|SwapIDPart=Ž&Ž||PinPropagationDelay=0.000000E+000
|RECORD=2|OwnerIndex=1222|OwnerPartId=1|FormalType=1|Electrical=4|PinConglomerate=58|PinLength=30|Location.X=580|Location.Y=960|Name=11|Designator=11|SwapIDPart=Ž&Ž||PinPropagationDelay=0.000000E+000
|RECORD=2|OwnerIndex=1222|OwnerPartId=1|FormalType=1|Electrical=4|PinConglomerate=58|PinLength=30|Location.X=580|Location.Y=950|Name=12|Designator=12|SwapIDPart=Ž&Ž||PinPropagationDelay=0.000000E+000
|RECORD=2|OwnerIndex=1222|OwnerPartId=1|FormalType=1|Electrical=4|PinConglomerate=56|PinLength=30|Location.X=630|Location.Y=980|Name=13|Designator=13|SwapIDPart=Ž&Ž||PinPropagationDelay=0.000000E+000
|RECORD=2|OwnerIndex=1222|OwnerPartId=1|FormalType=1|Electrical=4|PinConglomerate=56|PinLength=30|Location.X=630|Location.Y=970|Name=14|Designator=14|SwapIDPart=Ž&Ž||PinPropagationDelay=0.000000E+000
|RECORD=2|OwnerIndex=1222|OwnerPartId=1|FormalType=1|Electrical=4|PinConglomerate=56|PinLength=30|Location.X=630|Location.Y=960|Name=15|Designator=15|SwapIDPart=Ž&Ž||PinPropagationDelay=0.000000E+000
|RECORD=2|OwnerIndex=1222|OwnerPartId=1|FormalType=1|Electrical=4|PinConglomerate=56|PinLength=30|Location.X=630|Location.Y=950|Name=16|Designator=16|SwapIDPart=Ž&Ž||PinPropagationDelay=0.000000E+000
|RECORD=41|OwnerIndex=1222|IndexInSheet=18|OwnerPartId=-1|Location.X=580|Location.Y=920|Color=8388608|FontID=1|Text=SAM11878-ND|Name=Supplier Part Number 1|ReadOnlyState=3
|RECORD=34|OwnerIndex=1222|IndexInSheet=-1|OwnerPartId=-1|Location.X=580|Location.Y=1040|Color=8388608|FontID=1|Text=J6|Name=Designator|ReadOnlyState=1
|RECORD=41|OwnerIndex=1222|IndexInSheet=-1|OwnerPartId=-1|Location.X=580|Location.Y=930|Color=8388608|FontID=1|Text=GNSS Header 16-pin|Name=Comment
|RECORD=44|OwnerIndex=1222
|RECORD=45|OwnerIndex=1260|IndexInSheet=-1|ModelName=GNSS Header 16-pin|ModelType=PCBLIB|DatafileCount=1|ModelDatafileEntity0=GNSS Header 16-pin|ModelDatafileKind0=PCBLib|IsCurrent=T
|RECORD=46|OwnerIndex=1261
|RECORD=48|OwnerIndex=1261
|RECORD=1|LibReference=GNSS Header 16-pin|PartCount=2|DisplayModeCount=1|IndexInSheet=148|OwnerPartId=-1|Location.X=470|Location.Y=440|CurrentPartId=1|LibraryPath=*|SourceLibraryName=FPGA_CONN.SchLib|TargetFileName=*|AreaColor=11599871|Color=128|PartIDLocked=T|DesignItemId=GNSS Header 16-pin|AllPinCount=16
|RECORD=41|OwnerIndex=1264|OwnerPartId=-1|Location.X=438|Location.Y=530|Color=8388608|FontID=1|IsHidden=T|Text=Digi-Key|Name=Supplier 1|ReadOnlyState=3
|RECORD=14|OwnerIndex=1264|IsNotAccesible=T|IndexInSheet=1|OwnerPartId=1|Location.X=470|Location.Y=430|Corner.X=520|Corner.Y=530|Color=128|AreaColor=11599871|IsSolid=T
|RECORD=2|OwnerIndex=1264|OwnerPartId=1|FormalType=1|Electrical=4|PinConglomerate=58|PinLength=30|Location.X=470|Location.Y=520|Name=1|Designator=1|SwapIDPart=Ž&Ž||PinPropagationDelay=0.000000E+000
|RECORD=2|OwnerIndex=1264|OwnerPartId=1|FormalType=1|Electrical=4|PinConglomerate=58|PinLength=30|Location.X=470|Location.Y=510|Name=2|Designator=2|SwapIDPart=Ž&Ž||PinPropagationDelay=0.000000E+000
|RECORD=2|OwnerIndex=1264|OwnerPartId=1|FormalType=1|Electrical=4|PinConglomerate=58|PinLength=30|Location.X=470|Location.Y=500|Name=3|Designator=3|SwapIDPart=Ž&Ž||PinPropagationDelay=0.000000E+000
|RECORD=2|OwnerIndex=1264|OwnerPartId=1|FormalType=1|Electrical=4|PinConglomerate=58|PinLength=30|Location.X=470|Location.Y=490|Name=4|Designator=4|SwapIDPart=Ž&Ž||PinPropagationDelay=0.000000E+000
|RECORD=2|OwnerIndex=1264|OwnerPartId=1|FormalType=1|Electrical=4|PinConglomerate=56|PinLength=30|Location.X=520|Location.Y=520|Name=5|Designator=5|SwapIDPart=Ž&Ž||PinPropagationDelay=0.000000E+000
|RECORD=2|OwnerIndex=1264|OwnerPartId=1|FormalType=1|Electrical=4|PinConglomerate=56|PinLength=30|Location.X=520|Location.Y=510|Name=6|Designator=6|SwapIDPart=Ž&Ž||PinPropagationDelay=0.000000E+000
|RECORD=2|OwnerIndex=1264|OwnerPartId=1|FormalType=1|Electrical=4|PinConglomerate=56|PinLength=30|Location.X=520|Location.Y=500|Name=7|Designator=7|SwapIDPart=Ž&Ž||PinPropagationDelay=0.000000E+000
|RECORD=2|OwnerIndex=1264|OwnerPartId=1|FormalType=1|Electrical=4|PinConglomerate=56|PinLength=30|Location.X=520|Location.Y=490|Name=8|Designator=8|SwapIDPart=Ž&Ž||PinPropagationDelay=0.000000E+000
|RECORD=2|OwnerIndex=1264|OwnerPartId=1|FormalType=1|Electrical=4|PinConglomerate=58|PinLength=30|Location.X=470|Location.Y=470|Name=9|Designator=9|SwapIDPart=Ž&Ž||PinPropagationDelay=0.000000E+000
|RECORD=2|OwnerIndex=1264|OwnerPartId=1|FormalType=1|Electrical=4|PinConglomerate=58|PinLength=30|Location.X=470|Location.Y=460|Name=10|Designator=10|SwapIDPart=Ž&Ž||PinPropagationDelay=0.000000E+000
|RECORD=2|OwnerIndex=1264|OwnerPartId=1|FormalType=1|Electrical=4|PinConglomerate=58|PinLength=30|Location.X=470|Location.Y=450|Name=11|Designator=11|SwapIDPart=Ž&Ž||PinPropagationDelay=0.000000E+000
|RECORD=2|OwnerIndex=1264|OwnerPartId=1|FormalType=1|Electrical=4|PinConglomerate=58|PinLength=30|Location.X=470|Location.Y=440|Name=12|Designator=12|SwapIDPart=Ž&Ž||PinPropagationDelay=0.000000E+000
|RECORD=2|OwnerIndex=1264|OwnerPartId=1|FormalType=1|Electrical=4|PinConglomerate=56|PinLength=30|Location.X=520|Location.Y=470|Name=13|Designator=13|SwapIDPart=Ž&Ž||PinPropagationDelay=0.000000E+000
|RECORD=2|OwnerIndex=1264|OwnerPartId=1|FormalType=1|Electrical=4|PinConglomerate=56|PinLength=30|Location.X=520|Location.Y=460|Name=14|Designator=14|SwapIDPart=Ž&Ž||PinPropagationDelay=0.000000E+000
|RECORD=2|OwnerIndex=1264|OwnerPartId=1|FormalType=1|Electrical=4|PinConglomerate=56|PinLength=30|Location.X=520|Location.Y=450|Name=15|Designator=15|SwapIDPart=Ž&Ž||PinPropagationDelay=0.000000E+000
|RECORD=2|OwnerIndex=1264|OwnerPartId=1|FormalType=1|Electrical=4|PinConglomerate=56|PinLength=30|Location.X=520|Location.Y=440|Name=16|Designator=16|SwapIDPart=Ž&Ž||PinPropagationDelay=0.000000E+000
|RECORD=41|OwnerIndex=1264|IndexInSheet=18|OwnerPartId=-1|Location.X=470|Location.Y=410|Color=8388608|FontID=1|Text=SAM11878-ND|Name=Supplier Part Number 1|ReadOnlyState=3
|RECORD=34|OwnerIndex=1264|IndexInSheet=-1|OwnerPartId=-1|Location.X=470|Location.Y=530|Color=8388608|FontID=1|Text=J13|Name=Designator|ReadOnlyState=1
|RECORD=41|OwnerIndex=1264|IndexInSheet=-1|OwnerPartId=-1|Location.X=470|Location.Y=420|Color=8388608|FontID=1|Text=GNSS Header 16-pin|Name=Comment
|RECORD=44|OwnerIndex=1264
|RECORD=45|OwnerIndex=1302|IndexInSheet=-1|ModelName=GNSS Header 16-pin|ModelType=PCBLIB|DatafileCount=1|ModelDatafileEntity0=GNSS Header 16-pin|ModelDatafileKind0=PCBLib|IsCurrent=T
|RECORD=46|OwnerIndex=1303
|RECORD=48|OwnerIndex=1303
|RECORD=17|IndexInSheet=149|OwnerPartId=-1|ShowNetName=T|Location.X=200|Location.Y=490|Orientation=1|Color=128|FontID=1|Text=+5.0V
|RECORD=17|IndexInSheet=150|OwnerPartId=-1|ShowNetName=T|Location.X=100|Location.Y=490|Orientation=1|Color=128|FontID=1|Text=+3.3V
|RECORD=17|IndexInSheet=151|OwnerPartId=-1|Style=4|ShowNetName=T|Location.X=100|Location.Y=410|Orientation=3|Color=128|FontID=1|Text=GND
|RECORD=17|IndexInSheet=152|OwnerPartId=-1|Style=4|ShowNetName=T|Location.X=200|Location.Y=410|Orientation=3|Color=128|FontID=1|Text=GND
|RECORD=1|LibReference=CAP|ComponentDescription=C0603X104K5RACAUTO|PartCount=2|DisplayModeCount=2|IndexInSheet=153|OwnerPartId=-1|Location.X=140|Location.Y=430|Orientation=1|CurrentPartId=1|SourceLibraryName=Altium Content Vault|TargetFileName=*|AreaColor=11599871|Color=128|PartIDLocked=F|DesignItemId=CMP-2006-00003-1|AllPinCount=2
|RECORD=2|OwnerIndex=1310|OwnerPartId=1|OwnerPartDisplayMode=1|FormalType=1|Electrical=4|PinConglomerate=35|PinLength=10|Location.X=150|Location.Y=430|Name=1|Designator=1|PinPropagationDelay=0.000000E+000
|RECORD=2|OwnerIndex=1310|OwnerPartId=1|OwnerPartDisplayMode=1|FormalType=1|Electrical=4|PinConglomerate=33|PinLength=10|Location.X=150|Location.Y=440|Name=2|Designator=2|PinPropagationDelay=0.000000E+000
|RECORD=13|OwnerIndex=1310|IsNotAccesible=T|IndexInSheet=2|OwnerPartId=1|OwnerPartDisplayMode=1|Location.X=158|Location.Y=430|Corner.X=142|Corner.Y=430|LineWidth=1|Color=16711680
|RECORD=13|OwnerIndex=1310|IsNotAccesible=T|IndexInSheet=3|OwnerPartId=1|OwnerPartDisplayMode=1|Location.X=150|Location.Y=434|Corner.X=150|Corner.Y=440|LineWidth=1|Color=16711680
|RECORD=12|OwnerIndex=1310|IsNotAccesible=T|IndexInSheet=4|OwnerPartId=1|OwnerPartDisplayMode=1|Location.X=150|Location.Y=450|Radius=16|LineWidth=1|StartAngle=241.000|EndAngle=270.000|Color=16711680
|RECORD=12|OwnerIndex=1310|IsNotAccesible=T|IndexInSheet=5|OwnerPartId=1|OwnerPartDisplayMode=1|Location.X=150|Location.Y=450|Radius=16|LineWidth=1|StartAngle=270.000|EndAngle=299.000|Color=16711680
|RECORD=2|OwnerIndex=1310|OwnerPartId=1|FormalType=1|Electrical=4|PinConglomerate=35|PinLength=10|Location.X=150|Location.Y=430|Name=1|Designator=1|PinPropagationDelay=0.000000E+000
|RECORD=2|OwnerIndex=1310|OwnerPartId=1|FormalType=1|Electrical=4|PinConglomerate=33|PinLength=10|Location.X=150|Location.Y=440|Name=2|Designator=2|PinPropagationDelay=0.000000E+000
|RECORD=13|OwnerIndex=1310|IsNotAccesible=T|IndexInSheet=8|OwnerPartId=1|Location.X=142|Location.Y=437|Corner.X=158|Corner.Y=437|LineWidth=1|Color=16711680
|RECORD=13|OwnerIndex=1310|IsNotAccesible=T|IndexInSheet=9|OwnerPartId=1|Location.X=158|Location.Y=433|Corner.X=142|Corner.Y=433|LineWidth=1|Color=16711680
|RECORD=6|OwnerIndex=1310|IsNotAccesible=T|IndexInSheet=10|OwnerPartId=1|LineWidth=1|Color=16711680|LocationCount=2|X1=150|Y1=430|X2=150|Y2=433
|RECORD=6|OwnerIndex=1310|IsNotAccesible=T|IndexInSheet=11|OwnerPartId=1|LineWidth=1|Color=16711680|LocationCount=2|X1=150|Y1=440|X2=150|Y2=437
|RECORD=41|OwnerIndex=1310|IndexInSheet=12|OwnerPartId=-1|Location.X=141|Location.Y=452|Color=8388608|FontID=1|IsHidden=T|Text=Kemet|Name=Manufacturer
|RECORD=41|OwnerIndex=1310|IndexInSheet=13|OwnerPartId=-1|Location.X=141|Location.Y=452|Color=8388608|FontID=1|IsHidden=T|Text=C0603X104K5RACAUTO|Name=Part Number
|RECORD=34|OwnerIndex=1310|IndexInSheet=-1|OwnerPartId=-1|Location.X=159|Location.Y=431|Color=8388608|FontID=1|Text=C57|Name=Designator|ReadOnlyState=1
|RECORD=41|OwnerIndex=1310|IndexInSheet=-1|OwnerPartId=-1|Location.X=159|Location.Y=421|Color=8388608|FontID=1|Text=0.1uF|Name=Comment
|RECORD=44|OwnerIndex=1310
|RECORD=45|OwnerIndex=1331|IndexInSheet=-1|Description=Chip Capacitor, 2-Leads, Body 1.60x0.80mm, IPC Low Density|UseComponentLibrary=T|ModelName=CAPC1608X87X45ML20T05|ModelType=PCBLIB|DatafileCount=1|ModelDatafileEntity0=CAPC1608X87X45ML20T05|ModelDatafileKind0=PCBLib|IsCurrent=T|DatalinksLocked=T|DatabaseDatalinksLocked=T
|RECORD=46|OwnerIndex=1332
|RECORD=48|OwnerIndex=1332
|RECORD=41|OwnerIndex=1334|IndexInSheet=-1|OwnerPartId=-1|Color=8388608|FontID=1|Text=2D|Name=Available Preview Images
|RECORD=45|OwnerIndex=1331|IndexInSheet=-1|Description=Chip Capacitor, 2-Leads, Body 1.60x0.80mm, IPC High Density|UseComponentLibrary=T|ModelName=CAPC1608X87X45LL20T05|ModelType=PCBLIB|DatafileCount=1|ModelDatafileEntity0=CAPC1608X87X45LL20T05|ModelDatafileKind0=PCBLib|DatalinksLocked=T|DatabaseDatalinksLocked=T
|RECORD=46|OwnerIndex=1336
|RECORD=48|OwnerIndex=1336
|RECORD=41|OwnerIndex=1338|IndexInSheet=-1|OwnerPartId=-1|Color=8388608|FontID=1|Text=2D|Name=Available Preview Images
|RECORD=45|OwnerIndex=1331|IndexInSheet=-1|Description=Chip Capacitor, 2-Leads, Body 1.60x0.80mm, IPC Medium Density|UseComponentLibrary=T|ModelName=CAPC1608X87X45NL20T05|ModelType=PCBLIB|DatafileCount=1|ModelDatafileEntity0=CAPC1608X87X45NL20T05|ModelDatafileKind0=PCBLib|DatalinksLocked=T|DatabaseDatalinksLocked=T
|RECORD=46|OwnerIndex=1340
|RECORD=48|OwnerIndex=1340
|RECORD=41|OwnerIndex=1342|IndexInSheet=-1|OwnerPartId=-1|Color=8388608|FontID=1|Text=2D|Name=Available Preview Images
|RECORD=1|LibReference=CAP|ComponentDescription=C0603X104K5RACAUTO|PartCount=2|DisplayModeCount=2|IndexInSheet=154|OwnerPartId=-1|Location.X=240|Location.Y=430|Orientation=1|CurrentPartId=1|SourceLibraryName=Altium Content Vault|TargetFileName=*|AreaColor=11599871|Color=128|PartIDLocked=F|DesignItemId=CMP-2006-00003-1|AllPinCount=2
|RECORD=2|OwnerIndex=1344|OwnerPartId=1|OwnerPartDisplayMode=1|FormalType=1|Electrical=4|PinConglomerate=35|PinLength=10|Location.X=250|Location.Y=430|Name=1|Designator=1|PinPropagationDelay=0.000000E+000
|RECORD=2|OwnerIndex=1344|OwnerPartId=1|OwnerPartDisplayMode=1|FormalType=1|Electrical=4|PinConglomerate=33|PinLength=10|Location.X=250|Location.Y=440|Name=2|Designator=2|PinPropagationDelay=0.000000E+000
|RECORD=13|OwnerIndex=1344|IsNotAccesible=T|IndexInSheet=2|OwnerPartId=1|OwnerPartDisplayMode=1|Location.X=258|Location.Y=430|Corner.X=242|Corner.Y=430|LineWidth=1|Color=16711680
|RECORD=13|OwnerIndex=1344|IsNotAccesible=T|IndexInSheet=3|OwnerPartId=1|OwnerPartDisplayMode=1|Location.X=250|Location.Y=434|Corner.X=250|Corner.Y=440|LineWidth=1|Color=16711680
|RECORD=12|OwnerIndex=1344|IsNotAccesible=T|IndexInSheet=4|OwnerPartId=1|OwnerPartDisplayMode=1|Location.X=250|Location.Y=450|Radius=16|LineWidth=1|StartAngle=241.000|EndAngle=270.000|Color=16711680
|RECORD=12|OwnerIndex=1344|IsNotAccesible=T|IndexInSheet=5|OwnerPartId=1|OwnerPartDisplayMode=1|Location.X=250|Location.Y=450|Radius=16|LineWidth=1|StartAngle=270.000|EndAngle=299.000|Color=16711680
|RECORD=2|OwnerIndex=1344|OwnerPartId=1|FormalType=1|Electrical=4|PinConglomerate=35|PinLength=10|Location.X=250|Location.Y=430|Name=1|Designator=1|PinPropagationDelay=0.000000E+000
|RECORD=2|OwnerIndex=1344|OwnerPartId=1|FormalType=1|Electrical=4|PinConglomerate=33|PinLength=10|Location.X=250|Location.Y=440|Name=2|Designator=2|PinPropagationDelay=0.000000E+000
|RECORD=13|OwnerIndex=1344|IsNotAccesible=T|IndexInSheet=8|OwnerPartId=1|Location.X=242|Location.Y=437|Corner.X=258|Corner.Y=437|LineWidth=1|Color=16711680
|RECORD=13|OwnerIndex=1344|IsNotAccesible=T|IndexInSheet=9|OwnerPartId=1|Location.X=258|Location.Y=433|Corner.X=242|Corner.Y=433|LineWidth=1|Color=16711680
|RECORD=6|OwnerIndex=1344|IsNotAccesible=T|IndexInSheet=10|OwnerPartId=1|LineWidth=1|Color=16711680|LocationCount=2|X1=250|Y1=430|X2=250|Y2=433
|RECORD=6|OwnerIndex=1344|IsNotAccesible=T|IndexInSheet=11|OwnerPartId=1|LineWidth=1|Color=16711680|LocationCount=2|X1=250|Y1=440|X2=250|Y2=437
|RECORD=41|OwnerIndex=1344|IndexInSheet=12|OwnerPartId=-1|Location.X=241|Location.Y=452|Color=8388608|FontID=1|IsHidden=T|Text=Kemet|Name=Manufacturer
|RECORD=41|OwnerIndex=1344|IndexInSheet=13|OwnerPartId=-1|Location.X=241|Location.Y=452|Color=8388608|FontID=1|IsHidden=T|Text=C0603X104K5RACAUTO|Name=Part Number
|RECORD=34|OwnerIndex=1344|IndexInSheet=-1|OwnerPartId=-1|Location.X=259|Location.Y=431|Color=8388608|FontID=1|Text=C64|Name=Designator|ReadOnlyState=1
|RECORD=41|OwnerIndex=1344|IndexInSheet=-1|OwnerPartId=-1|Location.X=259|Location.Y=421|Color=8388608|FontID=1|Text=0.1uF|Name=Comment
|RECORD=44|OwnerIndex=1344
|RECORD=45|OwnerIndex=1365|IndexInSheet=-1|Description=Chip Capacitor, 2-Leads, Body 1.60x0.80mm, IPC Low Density|UseComponentLibrary=T|ModelName=CAPC1608X87X45ML20T05|ModelType=PCBLIB|DatafileCount=1|ModelDatafileEntity0=CAPC1608X87X45ML20T05|ModelDatafileKind0=PCBLib|IsCurrent=T|DatalinksLocked=T|DatabaseDatalinksLocked=T
|RECORD=46|OwnerIndex=1366
|RECORD=48|OwnerIndex=1366
|RECORD=41|OwnerIndex=1368|IndexInSheet=-1|OwnerPartId=-1|Color=8388608|FontID=1|Text=2D|Name=Available Preview Images
|RECORD=45|OwnerIndex=1365|IndexInSheet=-1|Description=Chip Capacitor, 2-Leads, Body 1.60x0.80mm, IPC High Density|UseComponentLibrary=T|ModelName=CAPC1608X87X45LL20T05|ModelType=PCBLIB|DatafileCount=1|ModelDatafileEntity0=CAPC1608X87X45LL20T05|ModelDatafileKind0=PCBLib|DatalinksLocked=T|DatabaseDatalinksLocked=T
|RECORD=46|OwnerIndex=1370
|RECORD=48|OwnerIndex=1370
|RECORD=41|OwnerIndex=1372|IndexInSheet=-1|OwnerPartId=-1|Color=8388608|FontID=1|Text=2D|Name=Available Preview Images
|RECORD=45|OwnerIndex=1365|IndexInSheet=-1|Description=Chip Capacitor, 2-Leads, Body 1.60x0.80mm, IPC Medium Density|UseComponentLibrary=T|ModelName=CAPC1608X87X45NL20T05|ModelType=PCBLIB|DatafileCount=1|ModelDatafileEntity0=CAPC1608X87X45NL20T05|ModelDatafileKind0=PCBLib|DatalinksLocked=T|DatabaseDatalinksLocked=T
|RECORD=46|OwnerIndex=1374
|RECORD=48|OwnerIndex=1374
|RECORD=41|OwnerIndex=1376|IndexInSheet=-1|OwnerPartId=-1|Color=8388608|FontID=1|Text=2D|Name=Available Preview Images
|RECORD=1|LibReference=b4654b650e69147ec39a6b967a45e02|ComponentDescription=None|PartCount=2|DisplayModeCount=1|IndexInSheet=155|OwnerPartId=-1|Location.X=100|Location.Y=450|CurrentPartId=1|LibraryPath=*|SourceLibraryName=Altium Content Vault|TargetFileName=*|AreaColor=11599871|Color=128|PartIDLocked=T|DesignItemId=CMP-14477-000079-2|AllPinCount=2
|RECORD=2|OwnerIndex=1378|OwnerPartId=1|Electrical=4|PinConglomerate=49|PinLength=7|Location.X=100|Location.Y=443|Name=1|Designator=1|PinPropagationDelay=0.000000E+000
|RECORD=2|OwnerIndex=1378|OwnerPartId=1|Electrical=4|PinConglomerate=51|PinLength=6|Location.X=100|Location.Y=436|Name=2|Designator=2|PinPropagationDelay=0.000000E+000
|RECORD=13|OwnerIndex=1378|IsNotAccesible=T|IndexInSheet=2|OwnerPartId=1|Location.X=110|Location.Y=443|Corner.X=90|Corner.Y=443|LineWidth=1|Color=16711680
|RECORD=13|OwnerIndex=1378|IsNotAccesible=T|IndexInSheet=3|OwnerPartId=1|Location.X=110|Location.Y=437|Corner.X=90|Corner.Y=437|LineWidth=1|Color=16711680
|RECORD=13|OwnerIndex=1378|IsNotAccesible=T|IndexInSheet=4|OwnerPartId=1|Location.X=100|Location.Y=443|Corner.X=100|Corner.Y=446|LineWidth=1|Color=16711680
|RECORD=13|OwnerIndex=1378|IsNotAccesible=T|IndexInSheet=5|OwnerPartId=1|Location.X=100|Location.Y=436|Corner.X=100|Corner.Y=435|LineWidth=1|Color=16711680
|RECORD=41|OwnerIndex=1378|IndexInSheet=6|OwnerPartId=-1|Location.X=89|Location.Y=452|Color=8388608|FontID=1|IsHidden=T|Text=Tape and Reel|Name=Packaging
|RECORD=41|OwnerIndex=1378|IndexInSheet=7|OwnerPartId=-1|Location.X=89|Location.Y=452|Color=8388608|FontID=1|IsHidden=T|Text=10uF|Name=Capacitance
|RECORD=41|OwnerIndex=1378|IndexInSheet=8|OwnerPartId=-1|Location.X=89|Location.Y=452|Color=8388608|FontID=1|IsHidden=T|Text=25V|Name=Voltage Rating (DC)
|RECORD=41|OwnerIndex=1378|IndexInSheet=9|OwnerPartId=-1|Location.X=89|Location.Y=452|Color=8388608|FontID=1|IsHidden=T|Text=0.053inch|Name=Thickness
|RECORD=41|OwnerIndex=1378|IndexInSheet=10|OwnerPartId=-1|Location.X=89|Location.Y=452|Color=8388608|FontID=1|IsHidden=T|Text=Ceramic|Name=Resistor Type
|RECORD=41|OwnerIndex=1378|IndexInSheet=11|OwnerPartId=-1|Location.X=89|Location.Y=452|Color=8388608|FontID=1|IsHidden=T|Text=Yes|Name=RoHS Compliant
|RECORD=41|OwnerIndex=1378|IndexInSheet=12|OwnerPartId=-1|Location.X=89|Location.Y=452|Color=8388608|FontID=1|IsHidden=T|Text=Lead Free|Name=Lead Free
|RECORD=41|OwnerIndex=1378|IndexInSheet=13|OwnerPartId=-1|Location.X=89|Location.Y=452|Color=8388608|FontID=1|IsHidden=T|Text=No SVHC|Name=REACH SVHC
|RECORD=41|OwnerIndex=1378|IndexInSheet=14|OwnerPartId=-1|Location.X=89|Location.Y=452|Color=8388608|FontID=1|IsHidden=T|Text=2|Name=Number of Pins
|RECORD=41|OwnerIndex=1378|IndexInSheet=15|OwnerPartId=-1|Location.X=89|Location.Y=452|Color=8388608|FontID=1|IsHidden=T|Text=1|Name=Package Quantity
|RECORD=41|OwnerIndex=1378|IndexInSheet=16|OwnerPartId=-1|Location.X=89|Location.Y=452|Color=8388608|FontID=1|IsHidden=T|Text=Surface Mount|Name=Mount
|RECORD=41|OwnerIndex=1378|IndexInSheet=17|OwnerPartId=-1|Location.X=89|Location.Y=452|Color=8388608|FontID=1|IsHidden=T|Text=SMD/SMT|Name=Termination
|RECORD=41|OwnerIndex=1378|IndexInSheet=18|OwnerPartId=-1|Location.X=89|Location.Y=452|Color=8388608|FontID=1|IsHidden=T|Text=0.049inch|Name=Width
|RECORD=41|OwnerIndex=1378|IndexInSheet=19|OwnerPartId=-1|Location.X=89|Location.Y=452|Color=8388608|FontID=1|IsHidden=T|Text=85°C|Name=Max Operating Temperature
|RECORD=41|OwnerIndex=1378|IndexInSheet=20|OwnerPartId=-1|Location.X=89|Location.Y=452|Color=8388608|FontID=1|IsHidden=T|Text=0.079inch|Name=Length
|RECORD=41|OwnerIndex=1378|IndexInSheet=21|OwnerPartId=-1|Location.X=89|Location.Y=452|Color=8388608|FontID=1|IsHidden=T|Text=0805|Name=Case/Package
|RECORD=41|OwnerIndex=1378|IndexInSheet=22|OwnerPartId=-1|Location.X=89|Location.Y=452|Color=8388608|FontID=1|IsHidden=T|Text=25V|Name=Voltage Rating
|RECORD=41|OwnerIndex=1378|IndexInSheet=23|OwnerPartId=-1|Location.X=89|Location.Y=452|Color=8388608|FontID=1|IsHidden=T|Text=-55°C|Name=Min Operating Temperature
|RECORD=41|OwnerIndex=1378|IndexInSheet=24|OwnerPartId=-1|Location.X=89|Location.Y=452|Color=8388608|FontID=1|IsHidden=T|Text=10%|Name=Tolerance
|RECORD=41|OwnerIndex=1378|IndexInSheet=25|OwnerPartId=-1|Location.X=89|Location.Y=452|Color=8388608|FontID=1|IsHidden=T|Text=X7R|Name=Dielectric
|RECORD=41|OwnerIndex=1378|IndexInSheet=26|OwnerPartId=-1|Location.X=89|Location.Y=452|Color=8388608|FontID=1|IsHidden=T|Text=2012|Name=Case Code (Metric)
|RECORD=41|OwnerIndex=1378|IndexInSheet=27|OwnerPartId=-1|Location.X=89|Location.Y=452|Color=8388608|FontID=1|IsHidden=T|Text=0805|Name=Case Code (Imperial)
|RECORD=41|OwnerIndex=1378|IndexInSheet=28|OwnerPartId=-1|Location.X=89|Location.Y=452|Color=8388608|FontID=1|IsHidden=T|Text=1.25mm|Name=Height
|RECORD=41|OwnerIndex=1378|IndexInSheet=29|OwnerPartId=-1|Location.X=89|Location.Y=452|Color=8388608|FontID=1|IsHidden=T|Text=16V|Name=Voltage
|RECORD=41|OwnerIndex=1378|IndexInSheet=30|OwnerPartId=-1|Location.X=89|Location.Y=452|Color=8388608|FontID=1|IsHidden=T|Text=M|Name=Series
|RECORD=34|OwnerIndex=1378|IndexInSheet=-1|OwnerPartId=-1|Location.X=111|Location.Y=437|Color=8388608|FontID=1|Text=C55|Name=Designator|ReadOnlyState=1
|RECORD=41|OwnerIndex=1378|IndexInSheet=-1|OwnerPartId=1|Location.X=111|Location.Y=427|Color=8388608|FontID=1|Text=10uF|Name=Comment
|RECORD=44|OwnerIndex=1378
|RECORD=45|OwnerIndex=1414|IndexInSheet=-1|UseComponentLibrary=T|ModelName=FP-MK212BG-MFG|ModelType=PCBLIB|DatafileCount=1|ModelDatafileEntity0=FP-MK212BG-MFG|ModelDatafileKind0=PCBLib|IsCurrent=T|DatalinksLocked=T|DatabaseDatalinksLocked=T
|RECORD=46|OwnerIndex=1415
|RECORD=48|OwnerIndex=1415
|RECORD=45|OwnerIndex=1414|IndexInSheet=-1|UseComponentLibrary=T|ModelName=FP-MK212BG-IPC_C|ModelType=PCBLIB|DatafileCount=1|ModelDatafileEntity0=FP-MK212BG-IPC_C|ModelDatafileKind0=PCBLib|DatalinksLocked=T|DatabaseDatalinksLocked=T
|RECORD=46|OwnerIndex=1418
|RECORD=48|OwnerIndex=1418
|RECORD=45|OwnerIndex=1414|IndexInSheet=-1|UseComponentLibrary=T|ModelName=FP-MK212BG-IPC_B|ModelType=PCBLIB|DatafileCount=1|ModelDatafileEntity0=FP-MK212BG-IPC_B|ModelDatafileKind0=PCBLib|DatalinksLocked=T|DatabaseDatalinksLocked=T
|RECORD=46|OwnerIndex=1421
|RECORD=48|OwnerIndex=1421
|RECORD=45|OwnerIndex=1414|IndexInSheet=-1|UseComponentLibrary=T|ModelName=FP-MK212BG-IPC_A|ModelType=PCBLIB|DatafileCount=1|ModelDatafileEntity0=FP-MK212BG-IPC_A|ModelDatafileKind0=PCBLib|DatalinksLocked=T|DatabaseDatalinksLocked=T
|RECORD=46|OwnerIndex=1424
|RECORD=48|OwnerIndex=1424
|RECORD=45|OwnerIndex=1414|IndexInSheet=-1|UseComponentLibrary=T|ModelName=TMK212BBJ106_G-T|ModelType=SIM|IsCurrent=T|DatalinksLocked=T|DatabaseDatalinksLocked=T
|RECORD=46|OwnerIndex=1427
|RECORD=48|OwnerIndex=1427
|RECORD=41|OwnerIndex=1429|IndexInSheet=-1|OwnerPartId=-1|Color=8388608|FontID=1|IsHidden=T|Text=General|Name=Kind
|RECORD=41|OwnerIndex=1429|IndexInSheet=-1|OwnerPartId=-1|Color=8388608|FontID=1|IsHidden=T|Text=Spice Subcircuit|Name=SubKind
|RECORD=41|OwnerIndex=1429|IndexInSheet=-1|OwnerPartId=-1|Color=8388608|FontID=1|IsHidden=T|Name=Spice Prefix
|RECORD=41|OwnerIndex=1429|IndexInSheet=-1|OwnerPartId=-1|Color=8388608|FontID=1|IsHidden=T|Name=Excluded Parts
|RECORD=41|OwnerIndex=1429|IndexInSheet=-1|OwnerPartId=-1|Color=8388608|FontID=1|IsHidden=T|Name=Netlist
|RECORD=1|LibReference=b4654b650e69147ec39a6b967a45e02|ComponentDescription=None|PartCount=2|DisplayModeCount=1|IndexInSheet=156|OwnerPartId=-1|Location.X=200|Location.Y=450|CurrentPartId=1|LibraryPath=*|SourceLibraryName=Altium Content Vault|TargetFileName=*|AreaColor=11599871|Color=128|PartIDLocked=T|DesignItemId=CMP-14477-000079-2|AllPinCount=2
|RECORD=2|OwnerIndex=1435|OwnerPartId=1|Electrical=4|PinConglomerate=49|PinLength=7|Location.X=200|Location.Y=443|Name=1|Designator=1|PinPropagationDelay=0.000000E+000
|RECORD=2|OwnerIndex=1435|OwnerPartId=1|Electrical=4|PinConglomerate=51|PinLength=6|Location.X=200|Location.Y=436|Name=2|Designator=2|PinPropagationDelay=0.000000E+000
|RECORD=13|OwnerIndex=1435|IsNotAccesible=T|IndexInSheet=2|OwnerPartId=1|Location.X=210|Location.Y=443|Corner.X=190|Corner.Y=443|LineWidth=1|Color=16711680
|RECORD=13|OwnerIndex=1435|IsNotAccesible=T|IndexInSheet=3|OwnerPartId=1|Location.X=210|Location.Y=437|Corner.X=190|Corner.Y=437|LineWidth=1|Color=16711680
|RECORD=13|OwnerIndex=1435|IsNotAccesible=T|IndexInSheet=4|OwnerPartId=1|Location.X=200|Location.Y=443|Corner.X=200|Corner.Y=446|LineWidth=1|Color=16711680
|RECORD=13|OwnerIndex=1435|IsNotAccesible=T|IndexInSheet=5|OwnerPartId=1|Location.X=200|Location.Y=436|Corner.X=200|Corner.Y=435|LineWidth=1|Color=16711680
|RECORD=41|OwnerIndex=1435|IndexInSheet=6|OwnerPartId=-1|Location.X=189|Location.Y=452|Color=8388608|FontID=1|IsHidden=T|Text=Tape and Reel|Name=Packaging
|RECORD=41|OwnerIndex=1435|IndexInSheet=7|OwnerPartId=-1|Location.X=189|Location.Y=452|Color=8388608|FontID=1|IsHidden=T|Text=10uF|Name=Capacitance
|RECORD=41|OwnerIndex=1435|IndexInSheet=8|OwnerPartId=-1|Location.X=189|Location.Y=452|Color=8388608|FontID=1|IsHidden=T|Text=25V|Name=Voltage Rating (DC)
|RECORD=41|OwnerIndex=1435|IndexInSheet=9|OwnerPartId=-1|Location.X=189|Location.Y=452|Color=8388608|FontID=1|IsHidden=T|Text=0.053inch|Name=Thickness
|RECORD=41|OwnerIndex=1435|IndexInSheet=10|OwnerPartId=-1|Location.X=189|Location.Y=452|Color=8388608|FontID=1|IsHidden=T|Text=Ceramic|Name=Resistor Type
|RECORD=41|OwnerIndex=1435|IndexInSheet=11|OwnerPartId=-1|Location.X=189|Location.Y=452|Color=8388608|FontID=1|IsHidden=T|Text=Yes|Name=RoHS Compliant
|RECORD=41|OwnerIndex=1435|IndexInSheet=12|OwnerPartId=-1|Location.X=189|Location.Y=452|Color=8388608|FontID=1|IsHidden=T|Text=Lead Free|Name=Lead Free
|RECORD=41|OwnerIndex=1435|IndexInSheet=13|OwnerPartId=-1|Location.X=189|Location.Y=452|Color=8388608|FontID=1|IsHidden=T|Text=No SVHC|Name=REACH SVHC
|RECORD=41|OwnerIndex=1435|IndexInSheet=14|OwnerPartId=-1|Location.X=189|Location.Y=452|Color=8388608|FontID=1|IsHidden=T|Text=2|Name=Number of Pins
|RECORD=41|OwnerIndex=1435|IndexInSheet=15|OwnerPartId=-1|Location.X=189|Location.Y=452|Color=8388608|FontID=1|IsHidden=T|Text=1|Name=Package Quantity
|RECORD=41|OwnerIndex=1435|IndexInSheet=16|OwnerPartId=-1|Location.X=189|Location.Y=452|Color=8388608|FontID=1|IsHidden=T|Text=Surface Mount|Name=Mount
|RECORD=41|OwnerIndex=1435|IndexInSheet=17|OwnerPartId=-1|Location.X=189|Location.Y=452|Color=8388608|FontID=1|IsHidden=T|Text=SMD/SMT|Name=Termination
|RECORD=41|OwnerIndex=1435|IndexInSheet=18|OwnerPartId=-1|Location.X=189|Location.Y=452|Color=8388608|FontID=1|IsHidden=T|Text=0.049inch|Name=Width
|RECORD=41|OwnerIndex=1435|IndexInSheet=19|OwnerPartId=-1|Location.X=189|Location.Y=452|Color=8388608|FontID=1|IsHidden=T|Text=85°C|Name=Max Operating Temperature
|RECORD=41|OwnerIndex=1435|IndexInSheet=20|OwnerPartId=-1|Location.X=189|Location.Y=452|Color=8388608|FontID=1|IsHidden=T|Text=0.079inch|Name=Length
|RECORD=41|OwnerIndex=1435|IndexInSheet=21|OwnerPartId=-1|Location.X=189|Location.Y=452|Color=8388608|FontID=1|IsHidden=T|Text=0805|Name=Case/Package
|RECORD=41|OwnerIndex=1435|IndexInSheet=22|OwnerPartId=-1|Location.X=189|Location.Y=452|Color=8388608|FontID=1|IsHidden=T|Text=25V|Name=Voltage Rating
|RECORD=41|OwnerIndex=1435|IndexInSheet=23|OwnerPartId=-1|Location.X=189|Location.Y=452|Color=8388608|FontID=1|IsHidden=T|Text=-55°C|Name=Min Operating Temperature
|RECORD=41|OwnerIndex=1435|IndexInSheet=24|OwnerPartId=-1|Location.X=189|Location.Y=452|Color=8388608|FontID=1|IsHidden=T|Text=10%|Name=Tolerance
|RECORD=41|OwnerIndex=1435|IndexInSheet=25|OwnerPartId=-1|Location.X=189|Location.Y=452|Color=8388608|FontID=1|IsHidden=T|Text=X7R|Name=Dielectric
|RECORD=41|OwnerIndex=1435|IndexInSheet=26|OwnerPartId=-1|Location.X=189|Location.Y=452|Color=8388608|FontID=1|IsHidden=T|Text=2012|Name=Case Code (Metric)
|RECORD=41|OwnerIndex=1435|IndexInSheet=27|OwnerPartId=-1|Location.X=189|Location.Y=452|Color=8388608|FontID=1|IsHidden=T|Text=0805|Name=Case Code (Imperial)
|RECORD=41|OwnerIndex=1435|IndexInSheet=28|OwnerPartId=-1|Location.X=189|Location.Y=452|Color=8388608|FontID=1|IsHidden=T|Text=1.25mm|Name=Height
|RECORD=41|OwnerIndex=1435|IndexInSheet=29|OwnerPartId=-1|Location.X=189|Location.Y=452|Color=8388608|FontID=1|IsHidden=T|Text=16V|Name=Voltage
|RECORD=41|OwnerIndex=1435|IndexInSheet=30|OwnerPartId=-1|Location.X=189|Location.Y=452|Color=8388608|FontID=1|IsHidden=T|Text=M|Name=Series
|RECORD=34|OwnerIndex=1435|IndexInSheet=-1|OwnerPartId=-1|Location.X=211|Location.Y=437|Color=8388608|FontID=1|Text=C56|Name=Designator|ReadOnlyState=1
|RECORD=41|OwnerIndex=1435|IndexInSheet=-1|OwnerPartId=1|Location.X=211|Location.Y=427|Color=8388608|FontID=1|Text=10uF|Name=Comment
|RECORD=44|OwnerIndex=1435
|RECORD=45|OwnerIndex=1471|IndexInSheet=-1|UseComponentLibrary=T|ModelName=FP-MK212BG-MFG|ModelType=PCBLIB|DatafileCount=1|ModelDatafileEntity0=FP-MK212BG-MFG|ModelDatafileKind0=PCBLib|IsCurrent=T|DatalinksLocked=T|DatabaseDatalinksLocked=T
|RECORD=46|OwnerIndex=1472
|RECORD=48|OwnerIndex=1472
|RECORD=45|OwnerIndex=1471|IndexInSheet=-1|UseComponentLibrary=T|ModelName=FP-MK212BG-IPC_C|ModelType=PCBLIB|DatafileCount=1|ModelDatafileEntity0=FP-MK212BG-IPC_C|ModelDatafileKind0=PCBLib|DatalinksLocked=T|DatabaseDatalinksLocked=T
|RECORD=46|OwnerIndex=1475
|RECORD=48|OwnerIndex=1475
|RECORD=45|OwnerIndex=1471|IndexInSheet=-1|UseComponentLibrary=T|ModelName=FP-MK212BG-IPC_B|ModelType=PCBLIB|DatafileCount=1|ModelDatafileEntity0=FP-MK212BG-IPC_B|ModelDatafileKind0=PCBLib|DatalinksLocked=T|DatabaseDatalinksLocked=T
|RECORD=46|OwnerIndex=1478
|RECORD=48|OwnerIndex=1478
|RECORD=45|OwnerIndex=1471|IndexInSheet=-1|UseComponentLibrary=T|ModelName=FP-MK212BG-IPC_A|ModelType=PCBLIB|DatafileCount=1|ModelDatafileEntity0=FP-MK212BG-IPC_A|ModelDatafileKind0=PCBLib|DatalinksLocked=T|DatabaseDatalinksLocked=T
|RECORD=46|OwnerIndex=1481
|RECORD=48|OwnerIndex=1481
|RECORD=45|OwnerIndex=1471|IndexInSheet=-1|UseComponentLibrary=T|ModelName=TMK212BBJ106_G-T|ModelType=SIM|IsCurrent=T|DatalinksLocked=T|DatabaseDatalinksLocked=T
|RECORD=46|OwnerIndex=1484
|RECORD=48|OwnerIndex=1484
|RECORD=41|OwnerIndex=1486|IndexInSheet=-1|OwnerPartId=-1|Color=8388608|FontID=1|IsHidden=T|Text=General|Name=Kind
|RECORD=41|OwnerIndex=1486|IndexInSheet=-1|OwnerPartId=-1|Color=8388608|FontID=1|IsHidden=T|Text=Spice Subcircuit|Name=SubKind
|RECORD=41|OwnerIndex=1486|IndexInSheet=-1|OwnerPartId=-1|Color=8388608|FontID=1|IsHidden=T|Name=Spice Prefix
|RECORD=41|OwnerIndex=1486|IndexInSheet=-1|OwnerPartId=-1|Color=8388608|FontID=1|IsHidden=T|Name=Excluded Parts
|RECORD=41|OwnerIndex=1486|IndexInSheet=-1|OwnerPartId=-1|Color=8388608|FontID=1|IsHidden=T|Name=Netlist
|RECORD=17|IndexInSheet=157|OwnerPartId=-1|Style=4|ShowNetName=T|Location.X=590|Location.Y=410|Orientation=3|Color=128|FontID=1|Text=GND
|RECORD=17|IndexInSheet=158|OwnerPartId=-1|Style=4|ShowNetName=T|Location.X=680|Location.Y=930|Orientation=3|Color=128|FontID=1|Text=GND
|RECORD=17|IndexInSheet=159|OwnerPartId=-1|ShowNetName=T|Location.X=220|Location.Y=1000|Orientation=1|Color=128|FontID=1|Text=+5.0V
|RECORD=17|IndexInSheet=160|OwnerPartId=-1|ShowNetName=T|Location.X=120|Location.Y=1000|Orientation=1|Color=128|FontID=1|Text=+3.3V
|RECORD=17|IndexInSheet=161|OwnerPartId=-1|Style=4|ShowNetName=T|Location.X=120|Location.Y=920|Orientation=3|Color=128|FontID=1|Text=GND
|RECORD=17|IndexInSheet=162|OwnerPartId=-1|Style=4|ShowNetName=T|Location.X=220|Location.Y=920|Orientation=3|Color=128|FontID=1|Text=GND
|RECORD=1|LibReference=CAP|ComponentDescription=C0603X104K5RACAUTO|PartCount=2|DisplayModeCount=2|IndexInSheet=163|OwnerPartId=-1|Location.X=160|Location.Y=940|Orientation=1|CurrentPartId=1|SourceLibraryName=Altium Content Vault|TargetFileName=*|AreaColor=11599871|Color=128|PartIDLocked=F|DesignItemId=CMP-2006-00003-1|AllPinCount=2
|RECORD=2|OwnerIndex=1498|OwnerPartId=1|OwnerPartDisplayMode=1|FormalType=1|Electrical=4|PinConglomerate=35|PinLength=10|Location.X=170|Location.Y=940|Name=1|Designator=1|PinPropagationDelay=0.000000E+000
|RECORD=2|OwnerIndex=1498|OwnerPartId=1|OwnerPartDisplayMode=1|FormalType=1|Electrical=4|PinConglomerate=33|PinLength=10|Location.X=170|Location.Y=950|Name=2|Designator=2|PinPropagationDelay=0.000000E+000
|RECORD=13|OwnerIndex=1498|IsNotAccesible=T|IndexInSheet=2|OwnerPartId=1|OwnerPartDisplayMode=1|Location.X=178|Location.Y=940|Corner.X=162|Corner.Y=940|LineWidth=1|Color=16711680
|RECORD=13|OwnerIndex=1498|IsNotAccesible=T|IndexInSheet=3|OwnerPartId=1|OwnerPartDisplayMode=1|Location.X=170|Location.Y=944|Corner.X=170|Corner.Y=950|LineWidth=1|Color=16711680
|RECORD=12|OwnerIndex=1498|IsNotAccesible=T|IndexInSheet=4|OwnerPartId=1|OwnerPartDisplayMode=1|Location.X=170|Location.Y=960|Radius=16|LineWidth=1|StartAngle=241.000|EndAngle=270.000|Color=16711680
|RECORD=12|OwnerIndex=1498|IsNotAccesible=T|IndexInSheet=5|OwnerPartId=1|OwnerPartDisplayMode=1|Location.X=170|Location.Y=960|Radius=16|LineWidth=1|StartAngle=270.000|EndAngle=299.000|Color=16711680
|RECORD=2|OwnerIndex=1498|OwnerPartId=1|FormalType=1|Electrical=4|PinConglomerate=35|PinLength=10|Location.X=170|Location.Y=940|Name=1|Designator=1|PinPropagationDelay=0.000000E+000
|RECORD=2|OwnerIndex=1498|OwnerPartId=1|FormalType=1|Electrical=4|PinConglomerate=33|PinLength=10|Location.X=170|Location.Y=950|Name=2|Designator=2|PinPropagationDelay=0.000000E+000
|RECORD=13|OwnerIndex=1498|IsNotAccesible=T|IndexInSheet=8|OwnerPartId=1|Location.X=162|Location.Y=947|Corner.X=178|Corner.Y=947|LineWidth=1|Color=16711680
|RECORD=13|OwnerIndex=1498|IsNotAccesible=T|IndexInSheet=9|OwnerPartId=1|Location.X=178|Location.Y=943|Corner.X=162|Corner.Y=943|LineWidth=1|Color=16711680
|RECORD=6|OwnerIndex=1498|IsNotAccesible=T|IndexInSheet=10|OwnerPartId=1|LineWidth=1|Color=16711680|LocationCount=2|X1=170|Y1=940|X2=170|Y2=943
|RECORD=6|OwnerIndex=1498|IsNotAccesible=T|IndexInSheet=11|OwnerPartId=1|LineWidth=1|Color=16711680|LocationCount=2|X1=170|Y1=950|X2=170|Y2=947
|RECORD=41|OwnerIndex=1498|IndexInSheet=12|OwnerPartId=-1|Location.X=161|Location.Y=962|Color=8388608|FontID=1|IsHidden=T|Text=Kemet|Name=Manufacturer
|RECORD=41|OwnerIndex=1498|IndexInSheet=13|OwnerPartId=-1|Location.X=161|Location.Y=962|Color=8388608|FontID=1|IsHidden=T|Text=C0603X104K5RACAUTO|Name=Part Number
|RECORD=34|OwnerIndex=1498|IndexInSheet=-1|OwnerPartId=-1|Location.X=179|Location.Y=941|Color=8388608|FontID=1|Text=C43|Name=Designator|ReadOnlyState=1
|RECORD=41|OwnerIndex=1498|IndexInSheet=-1|OwnerPartId=-1|Location.X=179|Location.Y=931|Color=8388608|FontID=1|Text=0.1uF|Name=Comment
|RECORD=44|OwnerIndex=1498
|RECORD=45|OwnerIndex=1519|IndexInSheet=-1|Description=Chip Capacitor, 2-Leads, Body 1.60x0.80mm, IPC Low Density|UseComponentLibrary=T|ModelName=CAPC1608X87X45ML20T05|ModelType=PCBLIB|DatafileCount=1|ModelDatafileEntity0=CAPC1608X87X45ML20T05|ModelDatafileKind0=PCBLib|IsCurrent=T|DatalinksLocked=T|DatabaseDatalinksLocked=T
|RECORD=46|OwnerIndex=1520
|RECORD=48|OwnerIndex=1520
|RECORD=41|OwnerIndex=1522|IndexInSheet=-1|OwnerPartId=-1|Color=8388608|FontID=1|Text=2D|Name=Available Preview Images
|RECORD=45|OwnerIndex=1519|IndexInSheet=-1|Description=Chip Capacitor, 2-Leads, Body 1.60x0.80mm, IPC High Density|UseComponentLibrary=T|ModelName=CAPC1608X87X45LL20T05|ModelType=PCBLIB|DatafileCount=1|ModelDatafileEntity0=CAPC1608X87X45LL20T05|ModelDatafileKind0=PCBLib|DatalinksLocked=T|DatabaseDatalinksLocked=T
|RECORD=46|OwnerIndex=1524
|RECORD=48|OwnerIndex=1524
|RECORD=41|OwnerIndex=1526|IndexInSheet=-1|OwnerPartId=-1|Color=8388608|FontID=1|Text=2D|Name=Available Preview Images
|RECORD=45|OwnerIndex=1519|IndexInSheet=-1|Description=Chip Capacitor, 2-Leads, Body 1.60x0.80mm, IPC Medium Density|UseComponentLibrary=T|ModelName=CAPC1608X87X45NL20T05|ModelType=PCBLIB|DatafileCount=1|ModelDatafileEntity0=CAPC1608X87X45NL20T05|ModelDatafileKind0=PCBLib|DatalinksLocked=T|DatabaseDatalinksLocked=T
|RECORD=46|OwnerIndex=1528
|RECORD=48|OwnerIndex=1528
|RECORD=41|OwnerIndex=1530|IndexInSheet=-1|OwnerPartId=-1|Color=8388608|FontID=1|Text=2D|Name=Available Preview Images
|RECORD=1|LibReference=CAP|ComponentDescription=C0603X104K5RACAUTO|PartCount=2|DisplayModeCount=2|IndexInSheet=164|OwnerPartId=-1|Location.X=260|Location.Y=940|Orientation=1|CurrentPartId=1|SourceLibraryName=Altium Content Vault|TargetFileName=*|AreaColor=11599871|Color=128|PartIDLocked=F|DesignItemId=CMP-2006-00003-1|AllPinCount=2
|RECORD=2|OwnerIndex=1532|OwnerPartId=1|OwnerPartDisplayMode=1|FormalType=1|Electrical=4|PinConglomerate=35|PinLength=10|Location.X=270|Location.Y=940|Name=1|Designator=1|PinPropagationDelay=0.000000E+000
|RECORD=2|OwnerIndex=1532|OwnerPartId=1|OwnerPartDisplayMode=1|FormalType=1|Electrical=4|PinConglomerate=33|PinLength=10|Location.X=270|Location.Y=950|Name=2|Designator=2|PinPropagationDelay=0.000000E+000
|RECORD=13|OwnerIndex=1532|IsNotAccesible=T|IndexInSheet=2|OwnerPartId=1|OwnerPartDisplayMode=1|Location.X=278|Location.Y=940|Corner.X=262|Corner.Y=940|LineWidth=1|Color=16711680
|RECORD=13|OwnerIndex=1532|IsNotAccesible=T|IndexInSheet=3|OwnerPartId=1|OwnerPartDisplayMode=1|Location.X=270|Location.Y=944|Corner.X=270|Corner.Y=950|LineWidth=1|Color=16711680
|RECORD=12|OwnerIndex=1532|IsNotAccesible=T|IndexInSheet=4|OwnerPartId=1|OwnerPartDisplayMode=1|Location.X=270|Location.Y=960|Radius=16|LineWidth=1|StartAngle=241.000|EndAngle=270.000|Color=16711680
|RECORD=12|OwnerIndex=1532|IsNotAccesible=T|IndexInSheet=5|OwnerPartId=1|OwnerPartDisplayMode=1|Location.X=270|Location.Y=960|Radius=16|LineWidth=1|StartAngle=270.000|EndAngle=299.000|Color=16711680
|RECORD=2|OwnerIndex=1532|OwnerPartId=1|FormalType=1|Electrical=4|PinConglomerate=35|PinLength=10|Location.X=270|Location.Y=940|Name=1|Designator=1|PinPropagationDelay=0.000000E+000
|RECORD=2|OwnerIndex=1532|OwnerPartId=1|FormalType=1|Electrical=4|PinConglomerate=33|PinLength=10|Location.X=270|Location.Y=950|Name=2|Designator=2|PinPropagationDelay=0.000000E+000
|RECORD=13|OwnerIndex=1532|IsNotAccesible=T|IndexInSheet=8|OwnerPartId=1|Location.X=262|Location.Y=947|Corner.X=278|Corner.Y=947|LineWidth=1|Color=16711680
|RECORD=13|OwnerIndex=1532|IsNotAccesible=T|IndexInSheet=9|OwnerPartId=1|Location.X=278|Location.Y=943|Corner.X=262|Corner.Y=943|LineWidth=1|Color=16711680
|RECORD=6|OwnerIndex=1532|IsNotAccesible=T|IndexInSheet=10|OwnerPartId=1|LineWidth=1|Color=16711680|LocationCount=2|X1=270|Y1=940|X2=270|Y2=943
|RECORD=6|OwnerIndex=1532|IsNotAccesible=T|IndexInSheet=11|OwnerPartId=1|LineWidth=1|Color=16711680|LocationCount=2|X1=270|Y1=950|X2=270|Y2=947
|RECORD=41|OwnerIndex=1532|IndexInSheet=12|OwnerPartId=-1|Location.X=261|Location.Y=962|Color=8388608|FontID=1|IsHidden=T|Text=Kemet|Name=Manufacturer
|RECORD=41|OwnerIndex=1532|IndexInSheet=13|OwnerPartId=-1|Location.X=261|Location.Y=962|Color=8388608|FontID=1|IsHidden=T|Text=C0603X104K5RACAUTO|Name=Part Number
|RECORD=34|OwnerIndex=1532|IndexInSheet=-1|OwnerPartId=-1|Location.X=279|Location.Y=941|Color=8388608|FontID=1|Text=C54|Name=Designator|ReadOnlyState=1
|RECORD=41|OwnerIndex=1532|IndexInSheet=-1|OwnerPartId=-1|Location.X=279|Location.Y=931|Color=8388608|FontID=1|Text=0.1uF|Name=Comment
|RECORD=44|OwnerIndex=1532
|RECORD=45|OwnerIndex=1553|IndexInSheet=-1|Description=Chip Capacitor, 2-Leads, Body 1.60x0.80mm, IPC Low Density|UseComponentLibrary=T|ModelName=CAPC1608X87X45ML20T05|ModelType=PCBLIB|DatafileCount=1|ModelDatafileEntity0=CAPC1608X87X45ML20T05|ModelDatafileKind0=PCBLib|IsCurrent=T|DatalinksLocked=T|DatabaseDatalinksLocked=T
|RECORD=46|OwnerIndex=1554
|RECORD=48|OwnerIndex=1554
|RECORD=41|OwnerIndex=1556|IndexInSheet=-1|OwnerPartId=-1|Color=8388608|FontID=1|Text=2D|Name=Available Preview Images
|RECORD=45|OwnerIndex=1553|IndexInSheet=-1|Description=Chip Capacitor, 2-Leads, Body 1.60x0.80mm, IPC High Density|UseComponentLibrary=T|ModelName=CAPC1608X87X45LL20T05|ModelType=PCBLIB|DatafileCount=1|ModelDatafileEntity0=CAPC1608X87X45LL20T05|ModelDatafileKind0=PCBLib|DatalinksLocked=T|DatabaseDatalinksLocked=T
|RECORD=46|OwnerIndex=1558
|RECORD=48|OwnerIndex=1558
|RECORD=41|OwnerIndex=1560|IndexInSheet=-1|OwnerPartId=-1|Color=8388608|FontID=1|Text=2D|Name=Available Preview Images
|RECORD=45|OwnerIndex=1553|IndexInSheet=-1|Description=Chip Capacitor, 2-Leads, Body 1.60x0.80mm, IPC Medium Density|UseComponentLibrary=T|ModelName=CAPC1608X87X45NL20T05|ModelType=PCBLIB|DatafileCount=1|ModelDatafileEntity0=CAPC1608X87X45NL20T05|ModelDatafileKind0=PCBLib|DatalinksLocked=T|DatabaseDatalinksLocked=T
|RECORD=46|OwnerIndex=1562
|RECORD=48|OwnerIndex=1562
|RECORD=41|OwnerIndex=1564|IndexInSheet=-1|OwnerPartId=-1|Color=8388608|FontID=1|Text=2D|Name=Available Preview Images
|RECORD=1|LibReference=b4654b650e69147ec39a6b967a45e02|ComponentDescription=None|PartCount=2|DisplayModeCount=1|IndexInSheet=165|OwnerPartId=-1|Location.X=120|Location.Y=960|CurrentPartId=1|LibraryPath=*|SourceLibraryName=Altium Content Vault|TargetFileName=*|AreaColor=11599871|Color=128|PartIDLocked=T|DesignItemId=CMP-14477-000079-2|AllPinCount=2
|RECORD=2|OwnerIndex=1566|OwnerPartId=1|Electrical=4|PinConglomerate=49|PinLength=7|Location.X=120|Location.Y=953|Name=1|Designator=1|PinPropagationDelay=0.000000E+000
|RECORD=2|OwnerIndex=1566|OwnerPartId=1|Electrical=4|PinConglomerate=51|PinLength=6|Location.X=120|Location.Y=946|Name=2|Designator=2|PinPropagationDelay=0.000000E+000
|RECORD=13|OwnerIndex=1566|IsNotAccesible=T|IndexInSheet=2|OwnerPartId=1|Location.X=130|Location.Y=953|Corner.X=110|Corner.Y=953|LineWidth=1|Color=16711680
|RECORD=13|OwnerIndex=1566|IsNotAccesible=T|IndexInSheet=3|OwnerPartId=1|Location.X=130|Location.Y=947|Corner.X=110|Corner.Y=947|LineWidth=1|Color=16711680
|RECORD=13|OwnerIndex=1566|IsNotAccesible=T|IndexInSheet=4|OwnerPartId=1|Location.X=120|Location.Y=953|Corner.X=120|Corner.Y=956|LineWidth=1|Color=16711680
|RECORD=13|OwnerIndex=1566|IsNotAccesible=T|IndexInSheet=5|OwnerPartId=1|Location.X=120|Location.Y=946|Corner.X=120|Corner.Y=945|LineWidth=1|Color=16711680
|RECORD=41|OwnerIndex=1566|IndexInSheet=6|OwnerPartId=-1|Location.X=109|Location.Y=962|Color=8388608|FontID=1|IsHidden=T|Text=Tape and Reel|Name=Packaging
|RECORD=41|OwnerIndex=1566|IndexInSheet=7|OwnerPartId=-1|Location.X=109|Location.Y=962|Color=8388608|FontID=1|IsHidden=T|Text=10uF|Name=Capacitance
|RECORD=41|OwnerIndex=1566|IndexInSheet=8|OwnerPartId=-1|Location.X=109|Location.Y=962|Color=8388608|FontID=1|IsHidden=T|Text=25V|Name=Voltage Rating (DC)
|RECORD=41|OwnerIndex=1566|IndexInSheet=9|OwnerPartId=-1|Location.X=109|Location.Y=962|Color=8388608|FontID=1|IsHidden=T|Text=0.053inch|Name=Thickness
|RECORD=41|OwnerIndex=1566|IndexInSheet=10|OwnerPartId=-1|Location.X=109|Location.Y=962|Color=8388608|FontID=1|IsHidden=T|Text=Ceramic|Name=Resistor Type
|RECORD=41|OwnerIndex=1566|IndexInSheet=11|OwnerPartId=-1|Location.X=109|Location.Y=962|Color=8388608|FontID=1|IsHidden=T|Text=Yes|Name=RoHS Compliant
|RECORD=41|OwnerIndex=1566|IndexInSheet=12|OwnerPartId=-1|Location.X=109|Location.Y=962|Color=8388608|FontID=1|IsHidden=T|Text=Lead Free|Name=Lead Free
|RECORD=41|OwnerIndex=1566|IndexInSheet=13|OwnerPartId=-1|Location.X=109|Location.Y=962|Color=8388608|FontID=1|IsHidden=T|Text=No SVHC|Name=REACH SVHC
|RECORD=41|OwnerIndex=1566|IndexInSheet=14|OwnerPartId=-1|Location.X=109|Location.Y=962|Color=8388608|FontID=1|IsHidden=T|Text=2|Name=Number of Pins
|RECORD=41|OwnerIndex=1566|IndexInSheet=15|OwnerPartId=-1|Location.X=109|Location.Y=962|Color=8388608|FontID=1|IsHidden=T|Text=1|Name=Package Quantity
|RECORD=41|OwnerIndex=1566|IndexInSheet=16|OwnerPartId=-1|Location.X=109|Location.Y=962|Color=8388608|FontID=1|IsHidden=T|Text=Surface Mount|Name=Mount
|RECORD=41|OwnerIndex=1566|IndexInSheet=17|OwnerPartId=-1|Location.X=109|Location.Y=962|Color=8388608|FontID=1|IsHidden=T|Text=SMD/SMT|Name=Termination
|RECORD=41|OwnerIndex=1566|IndexInSheet=18|OwnerPartId=-1|Location.X=109|Location.Y=962|Color=8388608|FontID=1|IsHidden=T|Text=0.049inch|Name=Width
|RECORD=41|OwnerIndex=1566|IndexInSheet=19|OwnerPartId=-1|Location.X=109|Location.Y=962|Color=8388608|FontID=1|IsHidden=T|Text=85°C|Name=Max Operating Temperature
|RECORD=41|OwnerIndex=1566|IndexInSheet=20|OwnerPartId=-1|Location.X=109|Location.Y=962|Color=8388608|FontID=1|IsHidden=T|Text=0.079inch|Name=Length
|RECORD=41|OwnerIndex=1566|IndexInSheet=21|OwnerPartId=-1|Location.X=109|Location.Y=962|Color=8388608|FontID=1|IsHidden=T|Text=0805|Name=Case/Package
|RECORD=41|OwnerIndex=1566|IndexInSheet=22|OwnerPartId=-1|Location.X=109|Location.Y=962|Color=8388608|FontID=1|IsHidden=T|Text=25V|Name=Voltage Rating
|RECORD=41|OwnerIndex=1566|IndexInSheet=23|OwnerPartId=-1|Location.X=109|Location.Y=962|Color=8388608|FontID=1|IsHidden=T|Text=-55°C|Name=Min Operating Temperature
|RECORD=41|OwnerIndex=1566|IndexInSheet=24|OwnerPartId=-1|Location.X=109|Location.Y=962|Color=8388608|FontID=1|IsHidden=T|Text=10%|Name=Tolerance
|RECORD=41|OwnerIndex=1566|IndexInSheet=25|OwnerPartId=-1|Location.X=109|Location.Y=962|Color=8388608|FontID=1|IsHidden=T|Text=X7R|Name=Dielectric
|RECORD=41|OwnerIndex=1566|IndexInSheet=26|OwnerPartId=-1|Location.X=109|Location.Y=962|Color=8388608|FontID=1|IsHidden=T|Text=2012|Name=Case Code (Metric)
|RECORD=41|OwnerIndex=1566|IndexInSheet=27|OwnerPartId=-1|Location.X=109|Location.Y=962|Color=8388608|FontID=1|IsHidden=T|Text=0805|Name=Case Code (Imperial)
|RECORD=41|OwnerIndex=1566|IndexInSheet=28|OwnerPartId=-1|Location.X=109|Location.Y=962|Color=8388608|FontID=1|IsHidden=T|Text=1.25mm|Name=Height
|RECORD=41|OwnerIndex=1566|IndexInSheet=29|OwnerPartId=-1|Location.X=109|Location.Y=962|Color=8388608|FontID=1|IsHidden=T|Text=16V|Name=Voltage
|RECORD=41|OwnerIndex=1566|IndexInSheet=30|OwnerPartId=-1|Location.X=109|Location.Y=962|Color=8388608|FontID=1|IsHidden=T|Text=M|Name=Series
|RECORD=34|OwnerIndex=1566|IndexInSheet=-1|OwnerPartId=-1|Location.X=131|Location.Y=947|Color=8388608|FontID=1|Text=C41|Name=Designator|ReadOnlyState=1
|RECORD=41|OwnerIndex=1566|IndexInSheet=-1|OwnerPartId=1|Location.X=131|Location.Y=937|Color=8388608|FontID=1|Text=10uF|Name=Comment
|RECORD=44|OwnerIndex=1566
|RECORD=45|OwnerIndex=1602|IndexInSheet=-1|UseComponentLibrary=T|ModelName=FP-MK212BG-MFG|ModelType=PCBLIB|DatafileCount=1|ModelDatafileEntity0=FP-MK212BG-MFG|ModelDatafileKind0=PCBLib|IsCurrent=T|DatalinksLocked=T|DatabaseDatalinksLocked=T
|RECORD=46|OwnerIndex=1603
|RECORD=48|OwnerIndex=1603
|RECORD=45|OwnerIndex=1602|IndexInSheet=-1|UseComponentLibrary=T|ModelName=FP-MK212BG-IPC_C|ModelType=PCBLIB|DatafileCount=1|ModelDatafileEntity0=FP-MK212BG-IPC_C|ModelDatafileKind0=PCBLib|DatalinksLocked=T|DatabaseDatalinksLocked=T
|RECORD=46|OwnerIndex=1606
|RECORD=48|OwnerIndex=1606
|RECORD=45|OwnerIndex=1602|IndexInSheet=-1|UseComponentLibrary=T|ModelName=FP-MK212BG-IPC_B|ModelType=PCBLIB|DatafileCount=1|ModelDatafileEntity0=FP-MK212BG-IPC_B|ModelDatafileKind0=PCBLib|DatalinksLocked=T|DatabaseDatalinksLocked=T
|RECORD=46|OwnerIndex=1609
|RECORD=48|OwnerIndex=1609
|RECORD=45|OwnerIndex=1602|IndexInSheet=-1|UseComponentLibrary=T|ModelName=FP-MK212BG-IPC_A|ModelType=PCBLIB|DatafileCount=1|ModelDatafileEntity0=FP-MK212BG-IPC_A|ModelDatafileKind0=PCBLib|DatalinksLocked=T|DatabaseDatalinksLocked=T
|RECORD=46|OwnerIndex=1612
|RECORD=48|OwnerIndex=1612
|RECORD=45|OwnerIndex=1602|IndexInSheet=-1|UseComponentLibrary=T|ModelName=TMK212BBJ106_G-T|ModelType=SIM|IsCurrent=T|DatalinksLocked=T|DatabaseDatalinksLocked=T
|RECORD=46|OwnerIndex=1615
|RECORD=48|OwnerIndex=1615
|RECORD=41|OwnerIndex=1617|IndexInSheet=-1|OwnerPartId=-1|Color=8388608|FontID=1|IsHidden=T|Text=General|Name=Kind
|RECORD=41|OwnerIndex=1617|IndexInSheet=-1|OwnerPartId=-1|Color=8388608|FontID=1|IsHidden=T|Text=Spice Subcircuit|Name=SubKind
|RECORD=41|OwnerIndex=1617|IndexInSheet=-1|OwnerPartId=-1|Color=8388608|FontID=1|IsHidden=T|Name=Spice Prefix
|RECORD=41|OwnerIndex=1617|IndexInSheet=-1|OwnerPartId=-1|Color=8388608|FontID=1|IsHidden=T|Name=Excluded Parts
|RECORD=41|OwnerIndex=1617|IndexInSheet=-1|OwnerPartId=-1|Color=8388608|FontID=1|IsHidden=T|Name=Netlist
|RECORD=1|LibReference=b4654b650e69147ec39a6b967a45e02|ComponentDescription=None|PartCount=2|DisplayModeCount=1|IndexInSheet=166|OwnerPartId=-1|Location.X=220|Location.Y=960|CurrentPartId=1|LibraryPath=*|SourceLibraryName=Altium Content Vault|TargetFileName=*|AreaColor=11599871|Color=128|PartIDLocked=T|DesignItemId=CMP-14477-000079-2|AllPinCount=2
|RECORD=2|OwnerIndex=1623|OwnerPartId=1|Electrical=4|PinConglomerate=49|PinLength=7|Location.X=220|Location.Y=953|Name=1|Designator=1|PinPropagationDelay=0.000000E+000
|RECORD=2|OwnerIndex=1623|OwnerPartId=1|Electrical=4|PinConglomerate=51|PinLength=6|Location.X=220|Location.Y=946|Name=2|Designator=2|PinPropagationDelay=0.000000E+000
|RECORD=13|OwnerIndex=1623|IsNotAccesible=T|IndexInSheet=2|OwnerPartId=1|Location.X=230|Location.Y=953|Corner.X=210|Corner.Y=953|LineWidth=1|Color=16711680
|RECORD=13|OwnerIndex=1623|IsNotAccesible=T|IndexInSheet=3|OwnerPartId=1|Location.X=230|Location.Y=947|Corner.X=210|Corner.Y=947|LineWidth=1|Color=16711680
|RECORD=13|OwnerIndex=1623|IsNotAccesible=T|IndexInSheet=4|OwnerPartId=1|Location.X=220|Location.Y=953|Corner.X=220|Corner.Y=956|LineWidth=1|Color=16711680
|RECORD=13|OwnerIndex=1623|IsNotAccesible=T|IndexInSheet=5|OwnerPartId=1|Location.X=220|Location.Y=946|Corner.X=220|Corner.Y=945|LineWidth=1|Color=16711680
|RECORD=41|OwnerIndex=1623|IndexInSheet=6|OwnerPartId=-1|Location.X=209|Location.Y=962|Color=8388608|FontID=1|IsHidden=T|Text=Tape and Reel|Name=Packaging
|RECORD=41|OwnerIndex=1623|IndexInSheet=7|OwnerPartId=-1|Location.X=209|Location.Y=962|Color=8388608|FontID=1|IsHidden=T|Text=10uF|Name=Capacitance
|RECORD=41|OwnerIndex=1623|IndexInSheet=8|OwnerPartId=-1|Location.X=209|Location.Y=962|Color=8388608|FontID=1|IsHidden=T|Text=25V|Name=Voltage Rating (DC)
|RECORD=41|OwnerIndex=1623|IndexInSheet=9|OwnerPartId=-1|Location.X=209|Location.Y=962|Color=8388608|FontID=1|IsHidden=T|Text=0.053inch|Name=Thickness
|RECORD=41|OwnerIndex=1623|IndexInSheet=10|OwnerPartId=-1|Location.X=209|Location.Y=962|Color=8388608|FontID=1|IsHidden=T|Text=Ceramic|Name=Resistor Type
|RECORD=41|OwnerIndex=1623|IndexInSheet=11|OwnerPartId=-1|Location.X=209|Location.Y=962|Color=8388608|FontID=1|IsHidden=T|Text=Yes|Name=RoHS Compliant
|RECORD=41|OwnerIndex=1623|IndexInSheet=12|OwnerPartId=-1|Location.X=209|Location.Y=962|Color=8388608|FontID=1|IsHidden=T|Text=Lead Free|Name=Lead Free
|RECORD=41|OwnerIndex=1623|IndexInSheet=13|OwnerPartId=-1|Location.X=209|Location.Y=962|Color=8388608|FontID=1|IsHidden=T|Text=No SVHC|Name=REACH SVHC
|RECORD=41|OwnerIndex=1623|IndexInSheet=14|OwnerPartId=-1|Location.X=209|Location.Y=962|Color=8388608|FontID=1|IsHidden=T|Text=2|Name=Number of Pins
|RECORD=41|OwnerIndex=1623|IndexInSheet=15|OwnerPartId=-1|Location.X=209|Location.Y=962|Color=8388608|FontID=1|IsHidden=T|Text=1|Name=Package Quantity
|RECORD=41|OwnerIndex=1623|IndexInSheet=16|OwnerPartId=-1|Location.X=209|Location.Y=962|Color=8388608|FontID=1|IsHidden=T|Text=Surface Mount|Name=Mount
|RECORD=41|OwnerIndex=1623|IndexInSheet=17|OwnerPartId=-1|Location.X=209|Location.Y=962|Color=8388608|FontID=1|IsHidden=T|Text=SMD/SMT|Name=Termination
|RECORD=41|OwnerIndex=1623|IndexInSheet=18|OwnerPartId=-1|Location.X=209|Location.Y=962|Color=8388608|FontID=1|IsHidden=T|Text=0.049inch|Name=Width
|RECORD=41|OwnerIndex=1623|IndexInSheet=19|OwnerPartId=-1|Location.X=209|Location.Y=962|Color=8388608|FontID=1|IsHidden=T|Text=85°C|Name=Max Operating Temperature
|RECORD=41|OwnerIndex=1623|IndexInSheet=20|OwnerPartId=-1|Location.X=209|Location.Y=962|Color=8388608|FontID=1|IsHidden=T|Text=0.079inch|Name=Length
|RECORD=41|OwnerIndex=1623|IndexInSheet=21|OwnerPartId=-1|Location.X=209|Location.Y=962|Color=8388608|FontID=1|IsHidden=T|Text=0805|Name=Case/Package
|RECORD=41|OwnerIndex=1623|IndexInSheet=22|OwnerPartId=-1|Location.X=209|Location.Y=962|Color=8388608|FontID=1|IsHidden=T|Text=25V|Name=Voltage Rating
|RECORD=41|OwnerIndex=1623|IndexInSheet=23|OwnerPartId=-1|Location.X=209|Location.Y=962|Color=8388608|FontID=1|IsHidden=T|Text=-55°C|Name=Min Operating Temperature
|RECORD=41|OwnerIndex=1623|IndexInSheet=24|OwnerPartId=-1|Location.X=209|Location.Y=962|Color=8388608|FontID=1|IsHidden=T|Text=10%|Name=Tolerance
|RECORD=41|OwnerIndex=1623|IndexInSheet=25|OwnerPartId=-1|Location.X=209|Location.Y=962|Color=8388608|FontID=1|IsHidden=T|Text=X7R|Name=Dielectric
|RECORD=41|OwnerIndex=1623|IndexInSheet=26|OwnerPartId=-1|Location.X=209|Location.Y=962|Color=8388608|FontID=1|IsHidden=T|Text=2012|Name=Case Code (Metric)
|RECORD=41|OwnerIndex=1623|IndexInSheet=27|OwnerPartId=-1|Location.X=209|Location.Y=962|Color=8388608|FontID=1|IsHidden=T|Text=0805|Name=Case Code (Imperial)
|RECORD=41|OwnerIndex=1623|IndexInSheet=28|OwnerPartId=-1|Location.X=209|Location.Y=962|Color=8388608|FontID=1|IsHidden=T|Text=1.25mm|Name=Height
|RECORD=41|OwnerIndex=1623|IndexInSheet=29|OwnerPartId=-1|Location.X=209|Location.Y=962|Color=8388608|FontID=1|IsHidden=T|Text=16V|Name=Voltage
|RECORD=41|OwnerIndex=1623|IndexInSheet=30|OwnerPartId=-1|Location.X=209|Location.Y=962|Color=8388608|FontID=1|IsHidden=T|Text=M|Name=Series
|RECORD=34|OwnerIndex=1623|IndexInSheet=-1|OwnerPartId=-1|Location.X=231|Location.Y=947|Color=8388608|FontID=1|Text=C42|Name=Designator|ReadOnlyState=1
|RECORD=41|OwnerIndex=1623|IndexInSheet=-1|OwnerPartId=1|Location.X=231|Location.Y=937|Color=8388608|FontID=1|Text=10uF|Name=Comment
|RECORD=44|OwnerIndex=1623
|RECORD=45|OwnerIndex=1659|IndexInSheet=-1|UseComponentLibrary=T|ModelName=FP-MK212BG-MFG|ModelType=PCBLIB|DatafileCount=1|ModelDatafileEntity0=FP-MK212BG-MFG|ModelDatafileKind0=PCBLib|IsCurrent=T|DatalinksLocked=T|DatabaseDatalinksLocked=T
|RECORD=46|OwnerIndex=1660
|RECORD=48|OwnerIndex=1660
|RECORD=45|OwnerIndex=1659|IndexInSheet=-1|UseComponentLibrary=T|ModelName=FP-MK212BG-IPC_C|ModelType=PCBLIB|DatafileCount=1|ModelDatafileEntity0=FP-MK212BG-IPC_C|ModelDatafileKind0=PCBLib|DatalinksLocked=T|DatabaseDatalinksLocked=T
|RECORD=46|OwnerIndex=1663
|RECORD=48|OwnerIndex=1663
|RECORD=45|OwnerIndex=1659|IndexInSheet=-1|UseComponentLibrary=T|ModelName=FP-MK212BG-IPC_B|ModelType=PCBLIB|DatafileCount=1|ModelDatafileEntity0=FP-MK212BG-IPC_B|ModelDatafileKind0=PCBLib|DatalinksLocked=T|DatabaseDatalinksLocked=T
|RECORD=46|OwnerIndex=1666
|RECORD=48|OwnerIndex=1666
|RECORD=45|OwnerIndex=1659|IndexInSheet=-1|UseComponentLibrary=T|ModelName=FP-MK212BG-IPC_A|ModelType=PCBLIB|DatafileCount=1|ModelDatafileEntity0=FP-MK212BG-IPC_A|ModelDatafileKind0=PCBLib|DatalinksLocked=T|DatabaseDatalinksLocked=T
|RECORD=46|OwnerIndex=1669
|RECORD=48|OwnerIndex=1669
|RECORD=45|OwnerIndex=1659|IndexInSheet=-1|UseComponentLibrary=T|ModelName=TMK212BBJ106_G-T|ModelType=SIM|IsCurrent=T|DatalinksLocked=T|DatabaseDatalinksLocked=T
|RECORD=46|OwnerIndex=1672
|RECORD=48|OwnerIndex=1672
|RECORD=41|OwnerIndex=1674|IndexInSheet=-1|OwnerPartId=-1|Color=8388608|FontID=1|IsHidden=T|Text=General|Name=Kind
|RECORD=41|OwnerIndex=1674|IndexInSheet=-1|OwnerPartId=-1|Color=8388608|FontID=1|IsHidden=T|Text=Spice Subcircuit|Name=SubKind
|RECORD=41|OwnerIndex=1674|IndexInSheet=-1|OwnerPartId=-1|Color=8388608|FontID=1|IsHidden=T|Name=Spice Prefix
|RECORD=41|OwnerIndex=1674|IndexInSheet=-1|OwnerPartId=-1|Color=8388608|FontID=1|IsHidden=T|Name=Excluded Parts
|RECORD=41|OwnerIndex=1674|IndexInSheet=-1|OwnerPartId=-1|Color=8388608|FontID=1|IsHidden=T|Name=Netlist
|RECORD=17|IndexInSheet=167|OwnerPartId=-1|ShowNetName=T|Location.X=410|Location.Y=960|Orientation=2|Color=255|FontID=1|Text=GPS1_PIN11|IsCrossSheetConnector=T
|RECORD=17|IndexInSheet=168|OwnerPartId=-1|ShowNetName=T|Location.X=410|Location.Y=950|Orientation=2|Color=255|FontID=1|Text=GPS1_PIN12|IsCrossSheetConnector=T
|RECORD=17|IndexInSheet=169|OwnerPartId=-1|ShowNetName=T|Location.X=810|Location.Y=980|Color=255|FontID=1|Text=GPS1_PIN13|IsCrossSheetConnector=T
|RECORD=17|IndexInSheet=170|OwnerPartId=-1|ShowNetName=T|Location.X=810|Location.Y=970|Color=255|FontID=1|Text=GPS1_PIN14|IsCrossSheetConnector=T
|RECORD=17|IndexInSheet=171|OwnerPartId=-1|ShowNetName=T|Location.X=810|Location.Y=960|Color=255|FontID=1|Text=GPS1_PIN15|IsCrossSheetConnector=T
|RECORD=17|IndexInSheet=172|OwnerPartId=-1|ShowNetName=T|Location.X=370|Location.Y=450|Orientation=2|Color=255|FontID=1|Text=GPS2_PIN11|IsCrossSheetConnector=T
|RECORD=17|IndexInSheet=173|OwnerPartId=-1|ShowNetName=T|Location.X=370|Location.Y=440|Orientation=2|Color=255|FontID=1|Text=GPS2_PIN12|IsCrossSheetConnector=T
|RECORD=17|IndexInSheet=174|OwnerPartId=-1|ShowNetName=T|Location.X=640|Location.Y=470|Color=255|FontID=1|Text=GPS2_PIN13|IsCrossSheetConnector=T
|RECORD=17|IndexInSheet=175|OwnerPartId=-1|ShowNetName=T|Location.X=640|Location.Y=460|Color=255|FontID=1|Text=GPS2_PIN14|IsCrossSheetConnector=T
|RECORD=17|IndexInSheet=176|OwnerPartId=-1|ShowNetName=T|Location.X=640|Location.Y=450|Color=255|FontID=1|Text=GPS2_PIN15|IsCrossSheetConnector=T
|RECORD=1|LibReference=ba837af00a0b6167256f888b31462b1|ComponentDescription=IMU ACCEL/GYRO/MAG I2C 28LGA|PartCount=2|DisplayModeCount=1|IndexInSheet=177|OwnerPartId=-1|Location.X=1300|Location.Y=400|CurrentPartId=1|LibraryPath=*|SourceLibraryName=Altium Content Vault|TargetFileName=*|AreaColor=11599871|Color=128|PartIDLocked=T|DesignItemId=CMP-2000-05075-4|AllPinCount=28
|RECORD=14|OwnerIndex=1690|IsNotAccesible=T|OwnerPartId=1|Location.X=1320|Location.Y=180|Corner.X=1470|Corner.Y=410|LineWidth=1|Color=128|AreaColor=11599871|IsSolid=T
|RECORD=2|OwnerIndex=1690|OwnerPartId=1|Electrical=7|PinConglomerate=58|PinLength=20|Location.X=1320|Location.Y=400|Name=VDD|Designator=3|PinPropagationDelay=0.000000E+000
|RECORD=2|OwnerIndex=1690|OwnerPartId=1|Electrical=7|PinConglomerate=58|PinLength=20|Location.X=1320|Location.Y=390|Name=VDDIO|Designator=28|PinPropagationDelay=0.000000E+000
|RECORD=2|OwnerIndex=1690|OwnerPartId=1|Electrical=4|PinConglomerate=58|PinLength=20|Location.X=1320|Location.Y=370|Name=NC|Designator=1|PinPropagationDelay=0.000000E+000
|RECORD=2|OwnerIndex=1690|OwnerPartId=1|Electrical=1|PinConglomerate=58|PinLength=20|Location.X=1320|Location.Y=280|Name=SWDIO|Designator=7|PinPropagationDelay=0.000000E+000
|RECORD=2|OwnerIndex=1690|OwnerPartId=1|SymBol_InnerEdge=3|PinConglomerate=58|PinLength=20|Location.X=1320|Location.Y=270|Name=SWCLK|Designator=8|PinPropagationDelay=0.000000E+000
|RECORD=2|OwnerIndex=1690|OwnerPartId=1|Electrical=2|PinConglomerate=56|PinLength=20|Location.X=1470|Location.Y=270|Name=BL IND|Designator=10|PinPropagationDelay=0.000000E+000
|RECORD=2|OwnerIndex=1690|OwnerPartId=1|Electrical=4|PinConglomerate=58|PinLength=20|Location.X=1320|Location.Y=240|Name=NC|Designator=12|PinPropagationDelay=0.000000E+000
|RECORD=2|OwnerIndex=1690|OwnerPartId=1|Electrical=4|PinConglomerate=58|PinLength=20|Location.X=1320|Location.Y=230|Name=NC|Designator=13|PinPropagationDelay=0.000000E+000
|RECORD=2|OwnerIndex=1690|OwnerPartId=1|Electrical=4|PinConglomerate=56|PinLength=20|Location.X=1470|Location.Y=250|Name=NC|Designator=15|PinPropagationDelay=0.000000E+000
|RECORD=2|OwnerIndex=1690|OwnerPartId=1|Electrical=4|PinConglomerate=56|PinLength=20|Location.X=1470|Location.Y=240|Name=NC|Designator=16|PinPropagationDelay=0.000000E+000
|RECORD=2|OwnerIndex=1690|OwnerPartId=1|Electrical=4|PinConglomerate=56|PinLength=20|Location.X=1470|Location.Y=220|Name=NC|Designator=21|PinPropagationDelay=0.000000E+000
|RECORD=2|OwnerIndex=1690|OwnerPartId=1|Electrical=4|PinConglomerate=56|PinLength=20|Location.X=1470|Location.Y=230|Name=NC|Designator=22|PinPropagationDelay=0.000000E+000
|RECORD=2|OwnerIndex=1690|OwnerPartId=1|Electrical=4|PinConglomerate=58|PinLength=20|Location.X=1320|Location.Y=220|Name=NC|Designator=23|PinPropagationDelay=0.000000E+000
|RECORD=2|OwnerIndex=1690|OwnerPartId=1|Electrical=4|PinConglomerate=58|PinLength=20|Location.X=1320|Location.Y=210|Name=NC|Designator=24|PinPropagationDelay=0.000000E+000
|RECORD=2|OwnerIndex=1690|OwnerPartId=1|PinConglomerate=58|PinLength=20|Location.X=1320|Location.Y=310|Name=PS0|Designator=6|PinPropagationDelay=0.000000E+000
|RECORD=2|OwnerIndex=1690|OwnerPartId=1|PinConglomerate=58|PinLength=20|Location.X=1320|Location.Y=300|Name=PS1|Designator=5|PinPropagationDelay=0.000000E+000
|RECORD=2|OwnerIndex=1690|OwnerPartId=1|PinConglomerate=56|PinLength=20|Location.X=1470|Location.Y=400|Name=B\O\O\T\ \L\O\A\D\ \P\I\N\|Designator=4|PinPropagationDelay=0.000000E+000
|RECORD=2|OwnerIndex=1690|OwnerPartId=1|PinConglomerate=58|PinLength=20|Location.X=1320|Location.Y=350|Name=R\E\S\E\T\|Designator=11|PinPropagationDelay=0.000000E+000
|RECORD=2|OwnerIndex=1690|OwnerPartId=1|Electrical=4|PinConglomerate=56|PinLength=20|Location.X=1470|Location.Y=380|Name=CAP|Designator=9|PinPropagationDelay=0.000000E+000
|RECORD=2|OwnerIndex=1690|OwnerPartId=1|Electrical=4|PinConglomerate=56|PinLength=20|Location.X=1470|Location.Y=360|Name=INT|Designator=14|PinPropagationDelay=0.000000E+000
|RECORD=2|OwnerIndex=1690|OwnerPartId=1|PinConglomerate=58|PinLength=20|Location.X=1320|Location.Y=330|Name=XIN32|Designator=27|PinPropagationDelay=0.000000E+000
|RECORD=2|OwnerIndex=1690|OwnerPartId=1|Electrical=4|PinConglomerate=56|PinLength=20|Location.X=1470|Location.Y=340|Name=XOUT32|Designator=26|PinPropagationDelay=0.000000E+000
|RECORD=2|OwnerIndex=1690|OwnerPartId=1|Electrical=1|PinConglomerate=56|PinLength=20|Location.X=1470|Location.Y=320|Name=COM0|Designator=20|PinPropagationDelay=0.000000E+000
|RECORD=2|OwnerIndex=1690|OwnerPartId=1|Electrical=1|PinConglomerate=56|PinLength=20|Location.X=1470|Location.Y=310|Name=COM1|Designator=19|PinPropagationDelay=0.000000E+000
|RECORD=2|OwnerIndex=1690|OwnerPartId=1|Electrical=1|PinConglomerate=56|PinLength=20|Location.X=1470|Location.Y=300|Name=COM2|Designator=18|PinPropagationDelay=0.000000E+000
|RECORD=2|OwnerIndex=1690|OwnerPartId=1|PinConglomerate=56|PinLength=20|Location.X=1470|Location.Y=290|Name=COM3|Designator=17|PinPropagationDelay=0.000000E+000
|RECORD=2|OwnerIndex=1690|OwnerPartId=1|Electrical=7|PinConglomerate=56|PinLength=20|Location.X=1470|Location.Y=200|Name=GND|Designator=2|PinPropagationDelay=0.000000E+000
|RECORD=2|OwnerIndex=1690|OwnerPartId=1|Electrical=7|PinConglomerate=56|PinLength=20|Location.X=1470|Location.Y=190|Name=GNDIO|Designator=25|PinPropagationDelay=0.000000E+000
|RECORD=41|OwnerIndex=1690|IndexInSheet=29|OwnerPartId=-1|Location.X=1298|Location.Y=410|Color=8388608|FontID=1|IsHidden=T|Text=Tape and Reel|Name=Packaging
|RECORD=41|OwnerIndex=1690|IndexInSheet=30|OwnerPartId=-1|Location.X=1298|Location.Y=410|Color=8388608|FontID=1|IsHidden=T|Text=LGA|Name=Case/Package
|RECORD=41|OwnerIndex=1690|IndexInSheet=31|OwnerPartId=-1|Location.X=1298|Location.Y=410|Color=8388608|FontID=1|IsHidden=T|Text=-40°C|Name=Min Operating Temperature
|RECORD=41|OwnerIndex=1690|IndexInSheet=32|OwnerPartId=-1|Location.X=1298|Location.Y=410|Color=8388608|FontID=1|IsHidden=T|Text=Surface Mount|Name=Mount
|RECORD=41|OwnerIndex=1690|IndexInSheet=33|OwnerPartId=-1|Location.X=1298|Location.Y=410|Color=8388608|FontID=1|IsHidden=T|Text=Accelerometer|Name=Sensor Type
|RECORD=41|OwnerIndex=1690|IndexInSheet=34|OwnerPartId=-1|Location.X=1298|Location.Y=410|Color=8388608|FontID=1|IsHidden=T|Text=I2C|Name=Output Type
|RECORD=41|OwnerIndex=1690|IndexInSheet=35|OwnerPartId=-1|Location.X=1298|Location.Y=410|Color=8388608|FontID=1|IsHidden=T|Text=Lead Free|Name=Lead Free
|RECORD=41|OwnerIndex=1690|IndexInSheet=36|OwnerPartId=-1|Location.X=1298|Location.Y=410|Color=8388608|FontID=1|IsHidden=T|Text=85°C|Name=Max Operating Temperature
|RECORD=34|OwnerIndex=1690|IndexInSheet=-1|OwnerPartId=-1|Location.X=1320|Location.Y=410|Color=8388608|FontID=1|Text=U13|Name=Designator|ReadOnlyState=1
|RECORD=41|OwnerIndex=1690|IndexInSheet=-1|OwnerPartId=1|Location.X=1320|Location.Y=170|Color=8388608|FontID=1|Text=BNO055|Name=Comment
|RECORD=44|OwnerIndex=1690
|RECORD=45|OwnerIndex=1758|IndexInSheet=-1|UseComponentLibrary=T|ModelName=FP-BNO055-MFG|ModelType=PCBLIB|DatafileCount=1|ModelDatafileEntity0=FP-BNO055-MFG|ModelDatafileKind0=PCBLib|IsCurrent=T|DatalinksLocked=T|DatabaseDatalinksLocked=T
|RECORD=46|OwnerIndex=1759
|RECORD=48|OwnerIndex=1759
|RECORD=17|IndexInSheet=178|OwnerPartId=-1|Style=4|ShowNetName=T|Location.X=1510|Location.Y=170|Orientation=3|Color=128|FontID=1|Text=GND
|RECORD=17|IndexInSheet=179|OwnerPartId=-1|ShowNetName=T|Location.X=1120|Location.Y=440|Orientation=1|Color=128|FontID=1|Text=+3.3V
|RECORD=17|IndexInSheet=180|OwnerPartId=-1|ShowNetName=T|Location.X=1160|Location.Y=440|Orientation=1|Color=128|FontID=1|Text=+3.3V
|RECORD=17|IndexInSheet=181|OwnerPartId=-1|Style=4|ShowNetName=T|Location.X=1120|Location.Y=240|Orientation=3|Color=128|FontID=1|Text=GND
|RECORD=17|IndexInSheet=182|OwnerPartId=-1|Style=4|ShowNetName=T|Location.X=1160|Location.Y=240|Orientation=3|Color=128|FontID=1|Text=GND
|RECORD=17|IndexInSheet=183|OwnerPartId=-1|ShowNetName=T|Location.X=1640|Location.Y=470|Orientation=1|Color=128|FontID=1|Text=+3.3V
|RECORD=17|IndexInSheet=184|OwnerPartId=-1|Style=4|ShowNetName=T|Location.X=1640|Location.Y=210|Orientation=3|Color=128|FontID=1|Text=GND
|RECORD=17|IndexInSheet=185|OwnerPartId=-1|Style=4|ShowNetName=T|Location.X=1600|Location.Y=210|Orientation=3|Color=128|FontID=1|Text=GND
|RECORD=17|IndexInSheet=186|OwnerPartId=-1|ShowNetName=T|Location.X=1560|Location.Y=310|Color=255|FontID=1|Text=SCL|IsCrossSheetConnector=T
|RECORD=17|IndexInSheet=187|OwnerPartId=-1|ShowNetName=T|Location.X=1560|Location.Y=320|Color=255|FontID=1|Text=SDA|IsCrossSheetConnector=T
|RECORD=17|IndexInSheet=188|OwnerPartId=-1|ShowNetName=T|Location.X=1170|Location.Y=170|Orientation=1|Color=128|FontID=1|Text=+3.3V
|RECORD=17|IndexInSheet=189|OwnerPartId=-1|ShowNetName=T|Location.X=1110|Location.Y=340|Orientation=2|Color=255|FontID=1|Text=PCIE_PERST|IsCrossSheetConnector=T
|RECORD=1|LibReference=RES-2|ComponentDescription=Chip Resistor, 0 Ohm, 0.1 W, -55 to 155 degC, 0402 (1005 Metric), RoHS, Tape and Reel|PartCount=2|DisplayModeCount=1|IndexInSheet=190|OwnerPartId=-1|Location.X=1220|Location.Y=340|CurrentPartId=1|LibraryPath=*|SourceLibraryName=Altium Content Vault|TargetFileName=*|AreaColor=11599871|Color=128|PartIDLocked=T|DesignItemId=CMP-2000-07451-1|AllPinCount=2
|RECORD=2|OwnerIndex=1774|OwnerPartId=1|FormalType=1|Electrical=4|PinConglomerate=32|PinLength=10|Location.X=1240|Location.Y=340|Name=2|Designator=2|PinPropagationDelay=0.000000E+000
|RECORD=2|OwnerIndex=1774|OwnerPartId=1|FormalType=1|Electrical=4|PinConglomerate=34|PinLength=10|Location.X=1220|Location.Y=340|Name=1|Designator=1|PinPropagationDelay=0.000000E+000
|RECORD=6|OwnerIndex=1774|IsNotAccesible=T|IndexInSheet=2|OwnerPartId=1|LineWidth=1|Color=16711680|LocationCount=10|X1=1240|Y1=340|X2=1236|Y2=340|X3=1235|Y3=338|X4=1233|Y4=342|X5=1231|Y5=338|X6=1229|Y6=342|X7=1227|Y7=338|X8=1225|Y8=342|X9=1224|Y9=340|X10=1220|Y10=340
|RECORD=41|OwnerIndex=1774|IndexInSheet=3|OwnerPartId=-1|Location.X=1208|Location.Y=355|Color=8388608|FontID=1|IsHidden=T|Text=50V|Name=Voltage Rating (DC)
|RECORD=41|OwnerIndex=1774|IndexInSheet=4|OwnerPartId=-1|Location.X=1208|Location.Y=355|Color=8388608|FontID=1|IsHidden=T|Text=2|Name=Number of Terminations
|RECORD=41|OwnerIndex=1774|IndexInSheet=5|OwnerPartId=-1|Location.X=1208|Location.Y=355|Color=8388608|FontID=1|IsHidden=T|Text=SurfaceMount|Name=Mount
|RECORD=41|OwnerIndex=1774|IndexInSheet=6|OwnerPartId=-1|Location.X=1208|Location.Y=355|Color=8388608|FontID=1|IsHidden=T|Text=0.35mm|Name=Height
|RECORD=41|OwnerIndex=1774|IndexInSheet=7|OwnerPartId=-1|Location.X=1208|Location.Y=355|Color=8388608|FontID=1|IsHidden=T|Text=TapeandReel|Name=Packaging
|RECORD=41|OwnerIndex=1774|IndexInSheet=8|OwnerPartId=-1|Location.X=1208|Location.Y=355|Color=8388608|FontID=1|IsHidden=T|Text=Tin|Name=Contact Plating
|RECORD=41|OwnerIndex=1774|IndexInSheet=9|OwnerPartId=-1|Location.X=1208|Location.Y=355|Color=8388608|FontID=8|IsHidden=T|Text=http://www.panasonic.com/|Name=Manufacturer URL
|RECORD=41|OwnerIndex=1774|IndexInSheet=10|OwnerPartId=-1|Location.X=1208|Location.Y=355|Color=8388608|FontID=1|IsHidden=T|Text=ThickFilm|Name=Composition
|RECORD=41|OwnerIndex=1774|IndexInSheet=11|OwnerPartId=-1|Location.X=1208|Location.Y=355|Color=8388608|FontID=1|IsHidden=T|Text=155degC|Name=Max Operating Temperature
|RECORD=41|OwnerIndex=1774|IndexInSheet=12|OwnerPartId=-1|Location.X=1208|Location.Y=355|Color=8388608|FontID=1|IsHidden=T|Text=600ppm/??C|Name=Temperature Coefficient
|RECORD=41|OwnerIndex=1774|IndexInSheet=13|OwnerPartId=-1|Location.X=1208|Location.Y=355|Color=8388608|FontID=1|IsHidden=T|Text=NoSVHC|Name=REACH SVHC
|RECORD=41|OwnerIndex=1774|IndexInSheet=14|OwnerPartId=-1|Location.X=1208|Location.Y=355|Color=8388608|FontID=1|IsHidden=T|Text=0402|Name=Case/Package
|RECORD=41|OwnerIndex=1774|IndexInSheet=15|OwnerPartId=-1|Location.X=1208|Location.Y=355|Color=8388608|FontID=1|IsHidden=T|Text=100mW|Name=Max Power Dissipation
|RECORD=41|OwnerIndex=1774|IndexInSheet=16|OwnerPartId=-1|Location.X=1208|Location.Y=355|Color=8388608|FontID=1|IsHidden=T|Text=402|Name=Package Reference
|RECORD=41|OwnerIndex=1774|IndexInSheet=17|OwnerPartId=-1|Location.X=1208|Location.Y=355|Color=8388608|FontID=1|IsHidden=T|Text=0.5mm|Name=Depth
|RECORD=41|OwnerIndex=1774|IndexInSheet=18|OwnerPartId=-1|Location.X=1208|Location.Y=355|Color=8388608|FontID=1|IsHidden=T|Text=Panasonic|Name=Manufacturer
|RECORD=41|OwnerIndex=1774|IndexInSheet=19|OwnerPartId=-1|Location.X=1208|Location.Y=355|Color=8388608|FontID=1|IsHidden=T|Text=2-Pin Surface Mount Device, Body 1 x 0.5 mm|Name=Package Description
|RECORD=41|OwnerIndex=1774|IndexInSheet=20|OwnerPartId=-1|Location.X=1208|Location.Y=355|Color=8388608|FontID=8|IsHidden=T|Text=https://industrial.panasonic.com/cdbs/www-data/pdf/RDA0000/AOA0000C301.pdf|Name=Datasheet URL
|RECORD=41|OwnerIndex=1774|IndexInSheet=21|OwnerPartId=-1|Location.X=1208|Location.Y=355|Color=8388608|FontID=1|IsHidden=T|Text=True|Name=RoHSCompliant
|RECORD=41|OwnerIndex=1774|IndexInSheet=22|OwnerPartId=-1|Location.X=1208|Location.Y=355|Color=8388608|FontID=1|IsHidden=T|Text=0402|Name=Case Code (Imperial)
|RECORD=41|OwnerIndex=1774|IndexInSheet=23|OwnerPartId=-1|Location.X=1208|Location.Y=355|Color=8388608|FontID=1|IsHidden=T|Text=0mOhm|Name=Resistance
|RECORD=41|OwnerIndex=1774|IndexInSheet=24|OwnerPartId=-1|Location.X=1208|Location.Y=355|Color=8388608|FontID=1|IsHidden=T|Text=Not|Name=Military Standard
|RECORD=41|OwnerIndex=1774|IndexInSheet=25|OwnerPartId=-1|Location.X=1208|Location.Y=355|Color=8388608|FontID=1|IsHidden=T|Text=5%|Name=Tolerance
|RECORD=41|OwnerIndex=1774|IndexInSheet=26|OwnerPartId=-1|Location.X=1208|Location.Y=355|Color=8388608|FontID=1|IsHidden=T|Text=-55degC|Name=Min Operating Temperature
|RECORD=41|OwnerIndex=1774|IndexInSheet=27|OwnerPartId=-1|Location.X=1208|Location.Y=355|Color=8388608|FontID=1|IsHidden=T|Text=100mW|Name=Power Rating
|RECORD=41|OwnerIndex=1774|IndexInSheet=28|OwnerPartId=-1|Location.X=1208|Location.Y=355|Color=8388608|FontID=1|IsHidden=T|Text=03/2015|Name=Datasheet Version
|RECORD=41|OwnerIndex=1774|IndexInSheet=29|OwnerPartId=-1|Location.X=1208|Location.Y=355|Color=8388608|FontID=1|IsHidden=T|Text=1mm|Name=Length
|RECORD=41|OwnerIndex=1774|IndexInSheet=30|OwnerPartId=-1|Location.X=1208|Location.Y=355|Color=8388608|FontID=1|IsHidden=T|Text=1005|Name=Case Code (Metric)
|RECORD=41|OwnerIndex=1774|IndexInSheet=31|OwnerPartId=-1|Location.X=1208|Location.Y=355|Color=8388608|FontID=1|IsHidden=T|Text=SMD/SMT|Name=Termination
|RECORD=41|OwnerIndex=1774|IndexInSheet=32|OwnerPartId=-1|Location.X=1208|Location.Y=355|Color=8388608|FontID=1|IsHidden=T|Text=SurfaceMount|Name=Mounting Technology
|RECORD=41|OwnerIndex=1774|IndexInSheet=33|OwnerPartId=-1|Location.X=1208|Location.Y=355|Color=8388608|FontID=1|IsHidden=T|Text=50V|Name=Voltage Rating
|RECORD=41|OwnerIndex=1774|IndexInSheet=34|OwnerPartId=-1|Location.X=1208|Location.Y=355|Color=8388608|FontID=1|IsHidden=T|Text=0.02inch|Name=Width
|RECORD=41|OwnerIndex=1774|IndexInSheet=35|OwnerPartId=-1|Location.X=1208|Location.Y=355|Color=8388608|FontID=1|IsHidden=T|Text=1|Name=Package Quantity
|RECORD=41|OwnerIndex=1774|IndexInSheet=36|OwnerPartId=-1|Location.X=1208|Location.Y=355|Color=8388608|FontID=1|IsHidden=T|Text=LeadFree|Name=Lead Free
|RECORD=41|OwnerIndex=1774|IndexInSheet=37|OwnerPartId=-1|Location.X=1208|Location.Y=355|Color=8388608|FontID=1|IsHidden=T|Text=No|Name=Radiation Hardening
|RECORD=34|OwnerIndex=1774|IndexInSheet=-1|OwnerPartId=-1|Location.X=1200|Location.Y=340|Color=8388608|FontID=1|Text=R54|Name=Designator|ReadOnlyState=1
|RECORD=41|OwnerIndex=1774|IndexInSheet=-1|OwnerPartId=-1|Location.X=1240|Location.Y=340|Color=8388608|FontID=1|Text=0_1%_0402|Name=Comment
|RECORD=44|OwnerIndex=1774
|RECORD=45|OwnerIndex=1817|IndexInSheet=-1|Description=Chip Resistor, 2-Leads, Body 1.05x0.55mm, IPC High Density|UseComponentLibrary=T|ModelName=RESC1005X40X25LL05T05|ModelType=PCBLIB|DatafileCount=1|ModelDatafileEntity0=RESC1005X40X25LL05T05|ModelDatafileKind0=PCBLib|IsCurrent=T|DatalinksLocked=T|DatabaseDatalinksLocked=T
|RECORD=46|OwnerIndex=1818
|RECORD=48|OwnerIndex=1818
|RECORD=41|OwnerIndex=1820|IndexInSheet=-1|OwnerPartId=-1|Color=8388608|FontID=1|IsHidden=T|Text=2D|Name=Available Preview Images
|RECORD=45|OwnerIndex=1817|IndexInSheet=-1|Description=Chip Resistor, 2-Leads, Body 1.05x0.55mm, IPC Low Density|UseComponentLibrary=T|ModelName=RESC1005X40X25ML05T05|ModelType=PCBLIB|DatafileCount=1|ModelDatafileEntity0=RESC1005X40X25ML05T05|ModelDatafileKind0=PCBLib|DatalinksLocked=T|DatabaseDatalinksLocked=T
|RECORD=46|OwnerIndex=1822
|RECORD=48|OwnerIndex=1822
|RECORD=41|OwnerIndex=1824|IndexInSheet=-1|OwnerPartId=-1|Color=8388608|FontID=1|IsHidden=T|Text=2D|Name=Available Preview Images
|RECORD=45|OwnerIndex=1817|IndexInSheet=-1|Description=Chip Resistor, 2-Leads, Body 1.05x0.55mm, IPC Medium Density|UseComponentLibrary=T|ModelName=RESC1005X40X25NL05T05|ModelType=PCBLIB|DatafileCount=1|ModelDatafileEntity0=RESC1005X40X25NL05T05|ModelDatafileKind0=PCBLib|DatalinksLocked=T|DatabaseDatalinksLocked=T
|RECORD=46|OwnerIndex=1826
|RECORD=48|OwnerIndex=1826
|RECORD=41|OwnerIndex=1828|IndexInSheet=-1|OwnerPartId=-1|Color=8388608|FontID=1|IsHidden=T|Text=2D|Name=Available Preview Images
|RECORD=17|IndexInSheet=191|OwnerPartId=-1|ShowNetName=T|Location.X=1510|Location.Y=360|Color=255|FontID=1|Text=BNO_INT|IsCrossSheetConnector=T
|RECORD=17|IndexInSheet=192|OwnerPartId=-1|ShowNetName=T|Location.X=1530|Location.Y=460|Orientation=2|Color=255|FontID=1|Text=BNO_INT|IsCrossSheetConnector=T
|RECORD=17|IndexInSheet=193|OwnerPartId=-1|ShowNetName=T|Location.X=1570|Location.Y=270|Color=255|FontID=1|Text=BNO_BLIND|IsCrossSheetConnector=T
|RECORD=17|IndexInSheet=194|OwnerPartId=-1|ShowNetName=T|Location.X=1260|Location.Y=330|Orientation=2|Color=255|FontID=1|Text=BNO_XIN32|IsCrossSheetConnector=T
|RECORD=17|IndexInSheet=195|OwnerPartId=-1|ShowNetName=T|Location.X=1510|Location.Y=340|Color=255|FontID=1|Text=BNO_XOUT32|IsCrossSheetConnector=T
|RECORD=17|IndexInSheet=196|OwnerPartId=-1|ShowNetName=T|Location.X=1330|Location.Y=590|Orientation=2|Color=255|FontID=1|Text=BNO_XIN32|IsCrossSheetConnector=T
|RECORD=17|IndexInSheet=197|OwnerPartId=-1|ShowNetName=T|Location.X=1330|Location.Y=540|Orientation=2|Color=255|FontID=1|Text=BNO_XOUT32|IsCrossSheetConnector=T
|RECORD=17|IndexInSheet=198|OwnerPartId=-1|Style=1|ShowNetName=T|Location.X=1460|Location.Y=590|Color=255|FontID=1|Text=BNO_XIN32_C|IsCrossSheetConnector=T
|RECORD=17|IndexInSheet=199|OwnerPartId=-1|Style=1|ShowNetName=T|Location.X=1460|Location.Y=540|Color=255|FontID=1|Text=BNO_XOUT32_C|IsCrossSheetConnector=T
|RECORD=1|LibReference=RES-2|ComponentDescription=Chip Resistor, 4.7 KOhm, +/- 1%, 0.1 W, -55 to 155 degC, 0402 (1005 Metric), RoHS, Tape and Reel|PartCount=2|DisplayModeCount=1|IndexInSheet=200|OwnerPartId=-1|Location.X=1210|Location.Y=200|Orientation=1|CurrentPartId=1|LibraryPath=*|SourceLibraryName=Altium Content Vault|TargetFileName=*|AreaColor=11599871|Color=128|PartIDLocked=T|DesignItemId=CMP-2002-01154-4|AllPinCount=2
|RECORD=2|OwnerIndex=1839|OwnerPartId=1|FormalType=1|Electrical=4|PinConglomerate=33|PinLength=10|Location.X=1210|Location.Y=220|Name=2|Designator=2|PinPropagationDelay=0.000000E+000
|RECORD=2|OwnerIndex=1839|OwnerPartId=1|FormalType=1|Electrical=4|PinConglomerate=35|PinLength=10|Location.X=1210|Location.Y=200|Name=1|Designator=1|PinPropagationDelay=0.000000E+000
|RECORD=6|OwnerIndex=1839|IsNotAccesible=T|IndexInSheet=2|OwnerPartId=1|LineWidth=1|Color=16711680|LocationCount=10|X1=1210|Y1=220|X2=1210|Y2=216|X3=1212|Y3=215|X4=1208|Y4=213|X5=1212|Y5=211|X6=1208|Y6=209|X7=1212|Y7=207|X8=1208|Y8=205|X9=1210|Y9=204|X10=1210|Y10=200
|RECORD=41|OwnerIndex=1839|IndexInSheet=3|OwnerPartId=-1|Location.X=1207|Location.Y=232|Color=8388608|FontID=1|IsHidden=T|Text=0.35 mm|Name=Height
|RECORD=41|OwnerIndex=1839|IndexInSheet=4|OwnerPartId=-1|Location.X=1207|Location.Y=232|Color=8388608|FontID=1|IsHidden=T|Text=Surface Mount|Name=Mounting Technology
|RECORD=41|OwnerIndex=1839|IndexInSheet=5|OwnerPartId=-1|Location.X=1207|Location.Y=232|Color=8388608|FontID=1|IsHidden=T|Text=Yes|Name=REACH SVHC
|RECORD=41|OwnerIndex=1839|IndexInSheet=6|OwnerPartId=-1|Location.X=1207|Location.Y=232|Color=8388608|FontID=1|IsHidden=T|Text=4.7 KOhm|Name=Resistance
|RECORD=41|OwnerIndex=1839|IndexInSheet=7|OwnerPartId=-1|Location.X=1207|Location.Y=232|Color=8388608|FontID=1|IsHidden=T|Text=155 degC|Name=Max Operating Temperature
|RECORD=41|OwnerIndex=1839|IndexInSheet=8|OwnerPartId=-1|Location.X=1207|Location.Y=232|Color=8388608|FontID=1|IsHidden=T|Text=Manufacturer URL|Name=ComponentLink1Description
|RECORD=41|OwnerIndex=1839|IndexInSheet=9|OwnerPartId=-1|Location.X=1207|Location.Y=232|Color=8388608|FontID=1|IsHidden=T|Text=Datasheet|Name=ComponentLink2Description
|RECORD=41|OwnerIndex=1839|IndexInSheet=10|OwnerPartId=-1|Location.X=1207|Location.Y=232|Color=8388608|FontID=1|IsHidden=T|Text=2|Name=Pins
|RECORD=41|OwnerIndex=1839|IndexInSheet=11|OwnerPartId=-1|Location.X=1207|Location.Y=232|Color=8388608|FontID=1|IsHidden=T|Text=0402|Name=PackageReference
|RECORD=41|OwnerIndex=1839|IndexInSheet=12|OwnerPartId=-1|Location.X=1207|Location.Y=232|Color=8388608|FontID=1|IsHidden=T|Text=1%|Name=Tolerance
|RECORD=41|OwnerIndex=1839|IndexInSheet=13|OwnerPartId=-1|Location.X=1207|Location.Y=232|Color=8388608|FontID=1|IsHidden=T|Text=0402|Name=Case Code (Imperial)
|RECORD=41|OwnerIndex=1839|IndexInSheet=14|OwnerPartId=-1|Location.X=1207|Location.Y=232|Color=8388608|FontID=1|IsHidden=T|Text=1 mm|Name=Length
|RECORD=41|OwnerIndex=1839|IndexInSheet=15|OwnerPartId=-1|Location.X=1207|Location.Y=232|Color=8388608|FontID=1|IsHidden=T|Text=2-Pin Surface Mount Device, Body 1 x 0.5 mm|Name=PackageDescription
|RECORD=41|OwnerIndex=1839|IndexInSheet=16|OwnerPartId=-1|Location.X=1207|Location.Y=232|Color=8388608|FontID=1|IsHidden=T|Text=ERJ-2RKF4701X|Name=PartNumber
|RECORD=41|OwnerIndex=1839|IndexInSheet=17|OwnerPartId=-1|Location.X=1207|Location.Y=232|Color=8388608|FontID=1|IsHidden=T|Text=true|Name=RoHSCompliant
|RECORD=41|OwnerIndex=1839|IndexInSheet=18|OwnerPartId=-1|Location.X=1207|Location.Y=232|Color=8388608|FontID=1|IsHidden=T|Text=1|Name=Package Quantity
|RECORD=41|OwnerIndex=1839|IndexInSheet=19|OwnerPartId=-1|Location.X=1207|Location.Y=232|Color=8388608|FontID=1|IsHidden=T|Text=No|Name=Radiation Hardening
|RECORD=41|OwnerIndex=1839|IndexInSheet=20|OwnerPartId=-1|Location.X=1207|Location.Y=232|Color=8388608|FontID=1|IsHidden=T|Text=04/2015|Name=DatasheetVersion
|RECORD=41|OwnerIndex=1839|IndexInSheet=21|OwnerPartId=-1|Location.X=1207|Location.Y=232|Color=8388608|FontID=1|IsHidden=T|Text=0.5 mm|Name=Width
|RECORD=41|OwnerIndex=1839|IndexInSheet=22|OwnerPartId=-1|Location.X=1207|Location.Y=232|Color=8388608|FontID=1|IsHidden=T|Text=1005|Name=Case Code (Metric)
|RECORD=41|OwnerIndex=1839|IndexInSheet=23|OwnerPartId=-1|Location.X=1207|Location.Y=232|Color=8388608|FontID=1|IsHidden=T|Text=50 V|Name=Voltage Rating
|RECORD=41|OwnerIndex=1839|IndexInSheet=24|OwnerPartId=-1|Location.X=1207|Location.Y=232|Color=8388608|FontID=1|IsHidden=T|Text=0402|Name=Case\/Package
|RECORD=41|OwnerIndex=1839|IndexInSheet=25|OwnerPartId=-1|Location.X=1207|Location.Y=232|Color=8388608|FontID=1|IsHidden=T|Text=Surface Mount|Name=Mount
|RECORD=41|OwnerIndex=1839|IndexInSheet=26|OwnerPartId=-1|Location.X=1207|Location.Y=232|Color=8388608|FontID=8|IsHidden=T|Text=http://www.panasonic.com/|Name=ComponentLink1URL
|RECORD=41|OwnerIndex=1839|IndexInSheet=27|OwnerPartId=-1|Location.X=1207|Location.Y=232|Color=8388608|FontID=1|IsHidden=T|Text=-55 degC|Name=Min Operating Temperature
|RECORD=41|OwnerIndex=1839|IndexInSheet=28|OwnerPartId=-1|Location.X=1207|Location.Y=232|Color=8388608|FontID=1|IsHidden=T|Text=100 mW|Name=Power Rating
|RECORD=41|OwnerIndex=1839|IndexInSheet=29|OwnerPartId=-1|Location.X=1207|Location.Y=232|Color=8388608|FontID=1|IsHidden=T|Text=Cut Tape|Name=Packaging
|RECORD=41|OwnerIndex=1839|IndexInSheet=30|OwnerPartId=-1|Location.X=1207|Location.Y=232|Color=8388608|FontID=8|IsHidden=T|Text=http://industrial.panasonic.com/cdbs/www-data/pdf/RDA0000/AOA0000C86.pdf|Name=ComponentLink2URL
|RECORD=34|OwnerIndex=1839|IndexInSheet=-1|OwnerPartId=-1|Location.X=1210|Location.Y=180|Orientation=1|Color=8388608|FontID=2|Text=R57|Name=Designator|ReadOnlyState=1
|RECORD=41|OwnerIndex=1839|IndexInSheet=-1|OwnerPartId=-1|Location.X=1220|Location.Y=170|Orientation=1|Color=8388608|FontID=2|Text=4.7K_0402|Name=Comment
|RECORD=44|OwnerIndex=1839
|RECORD=45|OwnerIndex=1875|IndexInSheet=-1|Description=Chip Resistor, 2-Leads, Body 1.05x0.55mm, IPC High Density|UseComponentLibrary=T|ModelName=RESC1005X40X25LL05T05|ModelType=PCBLIB|DatafileCount=1|ModelDatafileEntity0=RESC1005X40X25LL05T05|ModelDatafileKind0=PCBLib|IsCurrent=T|DatalinksLocked=T|DatabaseDatalinksLocked=T
|RECORD=46|OwnerIndex=1876
|RECORD=48|OwnerIndex=1876
|RECORD=41|OwnerIndex=1878|IndexInSheet=-1|OwnerPartId=-1|Color=8388608|FontID=1|IsHidden=T|Text=2D|Name=Available Preview Images
|RECORD=45|OwnerIndex=1875|IndexInSheet=-1|Description=Chip Resistor, 2-Leads, Body 1.05x0.55mm, IPC Low Density|UseComponentLibrary=T|ModelName=RESC1005X40X25ML05T05|ModelType=PCBLIB|DatafileCount=1|ModelDatafileEntity0=RESC1005X40X25ML05T05|ModelDatafileKind0=PCBLib|DatalinksLocked=T|DatabaseDatalinksLocked=T
|RECORD=46|OwnerIndex=1880
|RECORD=48|OwnerIndex=1880
|RECORD=41|OwnerIndex=1882|IndexInSheet=-1|OwnerPartId=-1|Color=8388608|FontID=1|IsHidden=T|Text=2D|Name=Available Preview Images
|RECORD=45|OwnerIndex=1875|IndexInSheet=-1|Description=Chip Resistor, 2-Leads, Body 1.05x0.55mm, IPC Medium Density|UseComponentLibrary=T|ModelName=RESC1005X40X25NL05T05|ModelType=PCBLIB|DatafileCount=1|ModelDatafileEntity0=RESC1005X40X25NL05T05|ModelDatafileKind0=PCBLib|DatalinksLocked=T|DatabaseDatalinksLocked=T
|RECORD=46|OwnerIndex=1884
|RECORD=48|OwnerIndex=1884
|RECORD=41|OwnerIndex=1886|IndexInSheet=-1|OwnerPartId=-1|Color=8388608|FontID=1|IsHidden=T|Text=2D|Name=Available Preview Images
|RECORD=1|LibReference=RES-2|ComponentDescription=Chip Resistor, 4.7 KOhm, +/- 1%, 0.1 W, -55 to 155 degC, 0402 (1005 Metric), RoHS, Tape and Reel|PartCount=2|DisplayModeCount=1|IndexInSheet=201|OwnerPartId=-1|Location.X=1240|Location.Y=200|Orientation=1|CurrentPartId=1|LibraryPath=*|SourceLibraryName=Altium Content Vault|TargetFileName=*|AreaColor=11599871|Color=128|PartIDLocked=T|DesignItemId=CMP-2002-01154-4|AllPinCount=2
|RECORD=2|OwnerIndex=1888|OwnerPartId=1|FormalType=1|Electrical=4|PinConglomerate=33|PinLength=10|Location.X=1240|Location.Y=220|Name=2|Designator=2|PinPropagationDelay=0.000000E+000
|RECORD=2|OwnerIndex=1888|OwnerPartId=1|FormalType=1|Electrical=4|PinConglomerate=35|PinLength=10|Location.X=1240|Location.Y=200|Name=1|Designator=1|PinPropagationDelay=0.000000E+000
|RECORD=6|OwnerIndex=1888|IsNotAccesible=T|IndexInSheet=2|OwnerPartId=1|LineWidth=1|Color=16711680|LocationCount=10|X1=1240|Y1=220|X2=1240|Y2=216|X3=1242|Y3=215|X4=1238|Y4=213|X5=1242|Y5=211|X6=1238|Y6=209|X7=1242|Y7=207|X8=1238|Y8=205|X9=1240|Y9=204|X10=1240|Y10=200
|RECORD=41|OwnerIndex=1888|IndexInSheet=3|OwnerPartId=-1|Location.X=1237|Location.Y=232|Color=8388608|FontID=1|IsHidden=T|Text=0.35 mm|Name=Height
|RECORD=41|OwnerIndex=1888|IndexInSheet=4|OwnerPartId=-1|Location.X=1237|Location.Y=232|Color=8388608|FontID=1|IsHidden=T|Text=Surface Mount|Name=Mounting Technology
|RECORD=41|OwnerIndex=1888|IndexInSheet=5|OwnerPartId=-1|Location.X=1237|Location.Y=232|Color=8388608|FontID=1|IsHidden=T|Text=Yes|Name=REACH SVHC
|RECORD=41|OwnerIndex=1888|IndexInSheet=6|OwnerPartId=-1|Location.X=1237|Location.Y=232|Color=8388608|FontID=1|IsHidden=T|Text=4.7 KOhm|Name=Resistance
|RECORD=41|OwnerIndex=1888|IndexInSheet=7|OwnerPartId=-1|Location.X=1237|Location.Y=232|Color=8388608|FontID=1|IsHidden=T|Text=155 degC|Name=Max Operating Temperature
|RECORD=41|OwnerIndex=1888|IndexInSheet=8|OwnerPartId=-1|Location.X=1237|Location.Y=232|Color=8388608|FontID=1|IsHidden=T|Text=Manufacturer URL|Name=ComponentLink1Description
|RECORD=41|OwnerIndex=1888|IndexInSheet=9|OwnerPartId=-1|Location.X=1237|Location.Y=232|Color=8388608|FontID=1|IsHidden=T|Text=Datasheet|Name=ComponentLink2Description
|RECORD=41|OwnerIndex=1888|IndexInSheet=10|OwnerPartId=-1|Location.X=1237|Location.Y=232|Color=8388608|FontID=1|IsHidden=T|Text=2|Name=Pins
|RECORD=41|OwnerIndex=1888|IndexInSheet=11|OwnerPartId=-1|Location.X=1237|Location.Y=232|Color=8388608|FontID=1|IsHidden=T|Text=0402|Name=PackageReference
|RECORD=41|OwnerIndex=1888|IndexInSheet=12|OwnerPartId=-1|Location.X=1237|Location.Y=232|Color=8388608|FontID=1|IsHidden=T|Text=1%|Name=Tolerance
|RECORD=41|OwnerIndex=1888|IndexInSheet=13|OwnerPartId=-1|Location.X=1237|Location.Y=232|Color=8388608|FontID=1|IsHidden=T|Text=0402|Name=Case Code (Imperial)
|RECORD=41|OwnerIndex=1888|IndexInSheet=14|OwnerPartId=-1|Location.X=1237|Location.Y=232|Color=8388608|FontID=1|IsHidden=T|Text=1 mm|Name=Length
|RECORD=41|OwnerIndex=1888|IndexInSheet=15|OwnerPartId=-1|Location.X=1237|Location.Y=232|Color=8388608|FontID=1|IsHidden=T|Text=2-Pin Surface Mount Device, Body 1 x 0.5 mm|Name=PackageDescription
|RECORD=41|OwnerIndex=1888|IndexInSheet=16|OwnerPartId=-1|Location.X=1237|Location.Y=232|Color=8388608|FontID=1|IsHidden=T|Text=ERJ-2RKF4701X|Name=PartNumber
|RECORD=41|OwnerIndex=1888|IndexInSheet=17|OwnerPartId=-1|Location.X=1237|Location.Y=232|Color=8388608|FontID=1|IsHidden=T|Text=true|Name=RoHSCompliant
|RECORD=41|OwnerIndex=1888|IndexInSheet=18|OwnerPartId=-1|Location.X=1237|Location.Y=232|Color=8388608|FontID=1|IsHidden=T|Text=1|Name=Package Quantity
|RECORD=41|OwnerIndex=1888|IndexInSheet=19|OwnerPartId=-1|Location.X=1237|Location.Y=232|Color=8388608|FontID=1|IsHidden=T|Text=No|Name=Radiation Hardening
|RECORD=41|OwnerIndex=1888|IndexInSheet=20|OwnerPartId=-1|Location.X=1237|Location.Y=232|Color=8388608|FontID=1|IsHidden=T|Text=04/2015|Name=DatasheetVersion
|RECORD=41|OwnerIndex=1888|IndexInSheet=21|OwnerPartId=-1|Location.X=1237|Location.Y=232|Color=8388608|FontID=1|IsHidden=T|Text=0.5 mm|Name=Width
|RECORD=41|OwnerIndex=1888|IndexInSheet=22|OwnerPartId=-1|Location.X=1237|Location.Y=232|Color=8388608|FontID=1|IsHidden=T|Text=1005|Name=Case Code (Metric)
|RECORD=41|OwnerIndex=1888|IndexInSheet=23|OwnerPartId=-1|Location.X=1237|Location.Y=232|Color=8388608|FontID=1|IsHidden=T|Text=50 V|Name=Voltage Rating
|RECORD=41|OwnerIndex=1888|IndexInSheet=24|OwnerPartId=-1|Location.X=1237|Location.Y=232|Color=8388608|FontID=1|IsHidden=T|Text=0402|Name=Case\/Package
|RECORD=41|OwnerIndex=1888|IndexInSheet=25|OwnerPartId=-1|Location.X=1237|Location.Y=232|Color=8388608|FontID=1|IsHidden=T|Text=Surface Mount|Name=Mount
|RECORD=41|OwnerIndex=1888|IndexInSheet=26|OwnerPartId=-1|Location.X=1237|Location.Y=232|Color=8388608|FontID=8|IsHidden=T|Text=http://www.panasonic.com/|Name=ComponentLink1URL
|RECORD=41|OwnerIndex=1888|IndexInSheet=27|OwnerPartId=-1|Location.X=1237|Location.Y=232|Color=8388608|FontID=1|IsHidden=T|Text=-55 degC|Name=Min Operating Temperature
|RECORD=41|OwnerIndex=1888|IndexInSheet=28|OwnerPartId=-1|Location.X=1237|Location.Y=232|Color=8388608|FontID=1|IsHidden=T|Text=100 mW|Name=Power Rating
|RECORD=41|OwnerIndex=1888|IndexInSheet=29|OwnerPartId=-1|Location.X=1237|Location.Y=232|Color=8388608|FontID=1|IsHidden=T|Text=Cut Tape|Name=Packaging
|RECORD=41|OwnerIndex=1888|IndexInSheet=30|OwnerPartId=-1|Location.X=1237|Location.Y=232|Color=8388608|FontID=8|IsHidden=T|Text=http://industrial.panasonic.com/cdbs/www-data/pdf/RDA0000/AOA0000C86.pdf|Name=ComponentLink2URL
|RECORD=34|OwnerIndex=1888|IndexInSheet=-1|OwnerPartId=-1|Location.X=1240|Location.Y=180|Orientation=1|Color=8388608|FontID=2|Text=R58|Name=Designator|ReadOnlyState=1
|RECORD=41|OwnerIndex=1888|IndexInSheet=-1|OwnerPartId=-1|Location.X=1250|Location.Y=170|Orientation=1|Color=8388608|FontID=2|Text=4.7K_0402|Name=Comment
|RECORD=44|OwnerIndex=1888
|RECORD=45|OwnerIndex=1924|IndexInSheet=-1|Description=Chip Resistor, 2-Leads, Body 1.05x0.55mm, IPC High Density|UseComponentLibrary=T|ModelName=RESC1005X40X25LL05T05|ModelType=PCBLIB|DatafileCount=1|ModelDatafileEntity0=RESC1005X40X25LL05T05|ModelDatafileKind0=PCBLib|IsCurrent=T|DatalinksLocked=T|DatabaseDatalinksLocked=T
|RECORD=46|OwnerIndex=1925
|RECORD=48|OwnerIndex=1925
|RECORD=41|OwnerIndex=1927|IndexInSheet=-1|OwnerPartId=-1|Color=8388608|FontID=1|IsHidden=T|Text=2D|Name=Available Preview Images
|RECORD=45|OwnerIndex=1924|IndexInSheet=-1|Description=Chip Resistor, 2-Leads, Body 1.05x0.55mm, IPC Low Density|UseComponentLibrary=T|ModelName=RESC1005X40X25ML05T05|ModelType=PCBLIB|DatafileCount=1|ModelDatafileEntity0=RESC1005X40X25ML05T05|ModelDatafileKind0=PCBLib|DatalinksLocked=T|DatabaseDatalinksLocked=T
|RECORD=46|OwnerIndex=1929
|RECORD=48|OwnerIndex=1929
|RECORD=41|OwnerIndex=1931|IndexInSheet=-1|OwnerPartId=-1|Color=8388608|FontID=1|IsHidden=T|Text=2D|Name=Available Preview Images
|RECORD=45|OwnerIndex=1924|IndexInSheet=-1|Description=Chip Resistor, 2-Leads, Body 1.05x0.55mm, IPC Medium Density|UseComponentLibrary=T|ModelName=RESC1005X40X25NL05T05|ModelType=PCBLIB|DatafileCount=1|ModelDatafileEntity0=RESC1005X40X25NL05T05|ModelDatafileKind0=PCBLib|DatalinksLocked=T|DatabaseDatalinksLocked=T
|RECORD=46|OwnerIndex=1933
|RECORD=48|OwnerIndex=1933
|RECORD=41|OwnerIndex=1935|IndexInSheet=-1|OwnerPartId=-1|Color=8388608|FontID=1|IsHidden=T|Text=2D|Name=Available Preview Images
|RECORD=1|LibReference=RES-2|ComponentDescription=Chip Resistor, 4.7 KOhm, +/- 1%, 0.1 W, -55 to 155 degC, 0402 (1005 Metric), RoHS, Tape and Reel|PartCount=2|DisplayModeCount=1|IndexInSheet=202|OwnerPartId=-1|Location.X=1640|Location.Y=370|Orientation=1|CurrentPartId=1|LibraryPath=*|SourceLibraryName=Altium Content Vault|TargetFileName=*|AreaColor=11599871|Color=128|PartIDLocked=T|DesignItemId=CMP-2002-01154-4|AllPinCount=2
|RECORD=2|OwnerIndex=1937|OwnerPartId=1|FormalType=1|Electrical=4|PinConglomerate=33|PinLength=10|Location.X=1640|Location.Y=390|Name=2|Designator=2|PinPropagationDelay=0.000000E+000
|RECORD=2|OwnerIndex=1937|OwnerPartId=1|FormalType=1|Electrical=4|PinConglomerate=35|PinLength=10|Location.X=1640|Location.Y=370|Name=1|Designator=1|PinPropagationDelay=0.000000E+000
|RECORD=6|OwnerIndex=1937|IsNotAccesible=T|IndexInSheet=2|OwnerPartId=1|LineWidth=1|Color=16711680|LocationCount=10|X1=1640|Y1=390|X2=1640|Y2=386|X3=1642|Y3=385|X4=1638|Y4=383|X5=1642|Y5=381|X6=1638|Y6=379|X7=1642|Y7=377|X8=1638|Y8=375|X9=1640|Y9=374|X10=1640|Y10=370
|RECORD=41|OwnerIndex=1937|IndexInSheet=3|OwnerPartId=-1|Location.X=1637|Location.Y=402|Color=8388608|FontID=1|IsHidden=T|Text=0.35 mm|Name=Height
|RECORD=41|OwnerIndex=1937|IndexInSheet=4|OwnerPartId=-1|Location.X=1637|Location.Y=402|Color=8388608|FontID=1|IsHidden=T|Text=Surface Mount|Name=Mounting Technology
|RECORD=41|OwnerIndex=1937|IndexInSheet=5|OwnerPartId=-1|Location.X=1637|Location.Y=402|Color=8388608|FontID=1|IsHidden=T|Text=Yes|Name=REACH SVHC
|RECORD=41|OwnerIndex=1937|IndexInSheet=6|OwnerPartId=-1|Location.X=1637|Location.Y=402|Color=8388608|FontID=1|IsHidden=T|Text=4.7 KOhm|Name=Resistance
|RECORD=41|OwnerIndex=1937|IndexInSheet=7|OwnerPartId=-1|Location.X=1637|Location.Y=402|Color=8388608|FontID=1|IsHidden=T|Text=155 degC|Name=Max Operating Temperature
|RECORD=41|OwnerIndex=1937|IndexInSheet=8|OwnerPartId=-1|Location.X=1637|Location.Y=402|Color=8388608|FontID=1|IsHidden=T|Text=Manufacturer URL|Name=ComponentLink1Description
|RECORD=41|OwnerIndex=1937|IndexInSheet=9|OwnerPartId=-1|Location.X=1637|Location.Y=402|Color=8388608|FontID=1|IsHidden=T|Text=Datasheet|Name=ComponentLink2Description
|RECORD=41|OwnerIndex=1937|IndexInSheet=10|OwnerPartId=-1|Location.X=1637|Location.Y=402|Color=8388608|FontID=1|IsHidden=T|Text=2|Name=Pins
|RECORD=41|OwnerIndex=1937|IndexInSheet=11|OwnerPartId=-1|Location.X=1637|Location.Y=402|Color=8388608|FontID=1|IsHidden=T|Text=0402|Name=PackageReference
|RECORD=41|OwnerIndex=1937|IndexInSheet=12|OwnerPartId=-1|Location.X=1637|Location.Y=402|Color=8388608|FontID=1|IsHidden=T|Text=1%|Name=Tolerance
|RECORD=41|OwnerIndex=1937|IndexInSheet=13|OwnerPartId=-1|Location.X=1637|Location.Y=402|Color=8388608|FontID=1|IsHidden=T|Text=0402|Name=Case Code (Imperial)
|RECORD=41|OwnerIndex=1937|IndexInSheet=14|OwnerPartId=-1|Location.X=1637|Location.Y=402|Color=8388608|FontID=1|IsHidden=T|Text=1 mm|Name=Length
|RECORD=41|OwnerIndex=1937|IndexInSheet=15|OwnerPartId=-1|Location.X=1637|Location.Y=402|Color=8388608|FontID=1|IsHidden=T|Text=2-Pin Surface Mount Device, Body 1 x 0.5 mm|Name=PackageDescription
|RECORD=41|OwnerIndex=1937|IndexInSheet=16|OwnerPartId=-1|Location.X=1637|Location.Y=402|Color=8388608|FontID=1|IsHidden=T|Text=ERJ-2RKF4701X|Name=PartNumber
|RECORD=41|OwnerIndex=1937|IndexInSheet=17|OwnerPartId=-1|Location.X=1637|Location.Y=402|Color=8388608|FontID=1|IsHidden=T|Text=true|Name=RoHSCompliant
|RECORD=41|OwnerIndex=1937|IndexInSheet=18|OwnerPartId=-1|Location.X=1637|Location.Y=402|Color=8388608|FontID=1|IsHidden=T|Text=1|Name=Package Quantity
|RECORD=41|OwnerIndex=1937|IndexInSheet=19|OwnerPartId=-1|Location.X=1637|Location.Y=402|Color=8388608|FontID=1|IsHidden=T|Text=No|Name=Radiation Hardening
|RECORD=41|OwnerIndex=1937|IndexInSheet=20|OwnerPartId=-1|Location.X=1637|Location.Y=402|Color=8388608|FontID=1|IsHidden=T|Text=04/2015|Name=DatasheetVersion
|RECORD=41|OwnerIndex=1937|IndexInSheet=21|OwnerPartId=-1|Location.X=1637|Location.Y=402|Color=8388608|FontID=1|IsHidden=T|Text=0.5 mm|Name=Width
|RECORD=41|OwnerIndex=1937|IndexInSheet=22|OwnerPartId=-1|Location.X=1637|Location.Y=402|Color=8388608|FontID=1|IsHidden=T|Text=1005|Name=Case Code (Metric)
|RECORD=41|OwnerIndex=1937|IndexInSheet=23|OwnerPartId=-1|Location.X=1637|Location.Y=402|Color=8388608|FontID=1|IsHidden=T|Text=50 V|Name=Voltage Rating
|RECORD=41|OwnerIndex=1937|IndexInSheet=24|OwnerPartId=-1|Location.X=1637|Location.Y=402|Color=8388608|FontID=1|IsHidden=T|Text=0402|Name=Case\/Package
|RECORD=41|OwnerIndex=1937|IndexInSheet=25|OwnerPartId=-1|Location.X=1637|Location.Y=402|Color=8388608|FontID=1|IsHidden=T|Text=Surface Mount|Name=Mount
|RECORD=41|OwnerIndex=1937|IndexInSheet=26|OwnerPartId=-1|Location.X=1637|Location.Y=402|Color=8388608|FontID=8|IsHidden=T|Text=http://www.panasonic.com/|Name=ComponentLink1URL
|RECORD=41|OwnerIndex=1937|IndexInSheet=27|OwnerPartId=-1|Location.X=1637|Location.Y=402|Color=8388608|FontID=1|IsHidden=T|Text=-55 degC|Name=Min Operating Temperature
|RECORD=41|OwnerIndex=1937|IndexInSheet=28|OwnerPartId=-1|Location.X=1637|Location.Y=402|Color=8388608|FontID=1|IsHidden=T|Text=100 mW|Name=Power Rating
|RECORD=41|OwnerIndex=1937|IndexInSheet=29|OwnerPartId=-1|Location.X=1637|Location.Y=402|Color=8388608|FontID=1|IsHidden=T|Text=Cut Tape|Name=Packaging
|RECORD=41|OwnerIndex=1937|IndexInSheet=30|OwnerPartId=-1|Location.X=1637|Location.Y=402|Color=8388608|FontID=8|IsHidden=T|Text=http://industrial.panasonic.com/cdbs/www-data/pdf/RDA0000/AOA0000C86.pdf|Name=ComponentLink2URL
|RECORD=34|OwnerIndex=1937|IndexInSheet=-1|OwnerPartId=-1|Location.X=1640|Location.Y=350|Orientation=1|Color=8388608|FontID=2|Text=R53|Name=Designator|ReadOnlyState=1
|RECORD=41|OwnerIndex=1937|IndexInSheet=-1|OwnerPartId=-1|Location.X=1650|Location.Y=340|Orientation=1|Color=8388608|FontID=2|Text=4.7K_0402|Name=Comment
|RECORD=44|OwnerIndex=1937
|RECORD=45|OwnerIndex=1973|IndexInSheet=-1|Description=Chip Resistor, 2-Leads, Body 1.05x0.55mm, IPC High Density|UseComponentLibrary=T|ModelName=RESC1005X40X25LL05T05|ModelType=PCBLIB|DatafileCount=1|ModelDatafileEntity0=RESC1005X40X25LL05T05|ModelDatafileKind0=PCBLib|IsCurrent=T|DatalinksLocked=T|DatabaseDatalinksLocked=T
|RECORD=46|OwnerIndex=1974
|RECORD=48|OwnerIndex=1974
|RECORD=41|OwnerIndex=1976|IndexInSheet=-1|OwnerPartId=-1|Color=8388608|FontID=1|IsHidden=T|Text=2D|Name=Available Preview Images
|RECORD=45|OwnerIndex=1973|IndexInSheet=-1|Description=Chip Resistor, 2-Leads, Body 1.05x0.55mm, IPC Low Density|UseComponentLibrary=T|ModelName=RESC1005X40X25ML05T05|ModelType=PCBLIB|DatafileCount=1|ModelDatafileEntity0=RESC1005X40X25ML05T05|ModelDatafileKind0=PCBLib|DatalinksLocked=T|DatabaseDatalinksLocked=T
|RECORD=46|OwnerIndex=1978
|RECORD=48|OwnerIndex=1978
|RECORD=41|OwnerIndex=1980|IndexInSheet=-1|OwnerPartId=-1|Color=8388608|FontID=1|IsHidden=T|Text=2D|Name=Available Preview Images
|RECORD=45|OwnerIndex=1973|IndexInSheet=-1|Description=Chip Resistor, 2-Leads, Body 1.05x0.55mm, IPC Medium Density|UseComponentLibrary=T|ModelName=RESC1005X40X25NL05T05|ModelType=PCBLIB|DatafileCount=1|ModelDatafileEntity0=RESC1005X40X25NL05T05|ModelDatafileKind0=PCBLib|DatalinksLocked=T|DatabaseDatalinksLocked=T
|RECORD=46|OwnerIndex=1982
|RECORD=48|OwnerIndex=1982
|RECORD=41|OwnerIndex=1984|IndexInSheet=-1|OwnerPartId=-1|Color=8388608|FontID=1|IsHidden=T|Text=2D|Name=Available Preview Images
|RECORD=1|LibReference=RES-2|ComponentDescription=Chip Resistor, 4.7 KOhm, +/- 1%, 0.1 W, -55 to 155 degC, 0402 (1005 Metric), RoHS, Tape and Reel|PartCount=2|DisplayModeCount=1|IndexInSheet=203|OwnerPartId=-1|Location.X=1640|Location.Y=240|Orientation=1|CurrentPartId=1|LibraryPath=*|SourceLibraryName=Altium Content Vault|TargetFileName=*|AreaColor=11599871|Color=128|PartIDLocked=T|DesignItemId=CMP-2002-01154-4|AllPinCount=2|ComponentKindVersion2=5
|RECORD=2|OwnerIndex=1986|OwnerPartId=1|FormalType=1|Electrical=4|PinConglomerate=33|PinLength=10|Location.X=1640|Location.Y=260|Name=2|Designator=2|PinPropagationDelay=0.000000E+000
|RECORD=2|OwnerIndex=1986|OwnerPartId=1|FormalType=1|Electrical=4|PinConglomerate=35|PinLength=10|Location.X=1640|Location.Y=240|Name=1|Designator=1|PinPropagationDelay=0.000000E+000
|RECORD=6|OwnerIndex=1986|IsNotAccesible=T|IndexInSheet=2|OwnerPartId=1|LineWidth=1|Color=16711680|LocationCount=10|X1=1640|Y1=260|X2=1640|Y2=256|X3=1642|Y3=255|X4=1638|Y4=253|X5=1642|Y5=251|X6=1638|Y6=249|X7=1642|Y7=247|X8=1638|Y8=245|X9=1640|Y9=244|X10=1640|Y10=240
|RECORD=41|OwnerIndex=1986|IndexInSheet=3|OwnerPartId=-1|Location.X=1637|Location.Y=272|Color=8388608|FontID=1|IsHidden=T|Text=0.35 mm|Name=Height
|RECORD=41|OwnerIndex=1986|IndexInSheet=4|OwnerPartId=-1|Location.X=1637|Location.Y=272|Color=8388608|FontID=1|IsHidden=T|Text=Surface Mount|Name=Mounting Technology
|RECORD=41|OwnerIndex=1986|IndexInSheet=5|OwnerPartId=-1|Location.X=1637|Location.Y=272|Color=8388608|FontID=1|IsHidden=T|Text=Yes|Name=REACH SVHC
|RECORD=41|OwnerIndex=1986|IndexInSheet=6|OwnerPartId=-1|Location.X=1637|Location.Y=272|Color=8388608|FontID=1|IsHidden=T|Text=4.7 KOhm|Name=Resistance
|RECORD=41|OwnerIndex=1986|IndexInSheet=7|OwnerPartId=-1|Location.X=1637|Location.Y=272|Color=8388608|FontID=1|IsHidden=T|Text=155 degC|Name=Max Operating Temperature
|RECORD=41|OwnerIndex=1986|IndexInSheet=8|OwnerPartId=-1|Location.X=1637|Location.Y=272|Color=8388608|FontID=1|IsHidden=T|Text=Manufacturer URL|Name=ComponentLink1Description
|RECORD=41|OwnerIndex=1986|IndexInSheet=9|OwnerPartId=-1|Location.X=1637|Location.Y=272|Color=8388608|FontID=1|IsHidden=T|Text=Datasheet|Name=ComponentLink2Description
|RECORD=41|OwnerIndex=1986|IndexInSheet=10|OwnerPartId=-1|Location.X=1637|Location.Y=272|Color=8388608|FontID=1|IsHidden=T|Text=2|Name=Pins
|RECORD=41|OwnerIndex=1986|IndexInSheet=11|OwnerPartId=-1|Location.X=1637|Location.Y=272|Color=8388608|FontID=1|IsHidden=T|Text=0402|Name=PackageReference
|RECORD=41|OwnerIndex=1986|IndexInSheet=12|OwnerPartId=-1|Location.X=1637|Location.Y=272|Color=8388608|FontID=1|IsHidden=T|Text=1%|Name=Tolerance
|RECORD=41|OwnerIndex=1986|IndexInSheet=13|OwnerPartId=-1|Location.X=1637|Location.Y=272|Color=8388608|FontID=1|IsHidden=T|Text=0402|Name=Case Code (Imperial)
|RECORD=41|OwnerIndex=1986|IndexInSheet=14|OwnerPartId=-1|Location.X=1637|Location.Y=272|Color=8388608|FontID=1|IsHidden=T|Text=1 mm|Name=Length
|RECORD=41|OwnerIndex=1986|IndexInSheet=15|OwnerPartId=-1|Location.X=1637|Location.Y=272|Color=8388608|FontID=1|IsHidden=T|Text=2-Pin Surface Mount Device, Body 1 x 0.5 mm|Name=PackageDescription
|RECORD=41|OwnerIndex=1986|IndexInSheet=16|OwnerPartId=-1|Location.X=1637|Location.Y=272|Color=8388608|FontID=1|IsHidden=T|Text=ERJ-2RKF4701X|Name=PartNumber
|RECORD=41|OwnerIndex=1986|IndexInSheet=17|OwnerPartId=-1|Location.X=1637|Location.Y=272|Color=8388608|FontID=1|IsHidden=T|Text=true|Name=RoHSCompliant
|RECORD=41|OwnerIndex=1986|IndexInSheet=18|OwnerPartId=-1|Location.X=1637|Location.Y=272|Color=8388608|FontID=1|IsHidden=T|Text=1|Name=Package Quantity
|RECORD=41|OwnerIndex=1986|IndexInSheet=19|OwnerPartId=-1|Location.X=1637|Location.Y=272|Color=8388608|FontID=1|IsHidden=T|Text=No|Name=Radiation Hardening
|RECORD=41|OwnerIndex=1986|IndexInSheet=20|OwnerPartId=-1|Location.X=1637|Location.Y=272|Color=8388608|FontID=1|IsHidden=T|Text=04/2015|Name=DatasheetVersion
|RECORD=41|OwnerIndex=1986|IndexInSheet=21|OwnerPartId=-1|Location.X=1637|Location.Y=272|Color=8388608|FontID=1|IsHidden=T|Text=0.5 mm|Name=Width
|RECORD=41|OwnerIndex=1986|IndexInSheet=22|OwnerPartId=-1|Location.X=1637|Location.Y=272|Color=8388608|FontID=1|IsHidden=T|Text=1005|Name=Case Code (Metric)
|RECORD=41|OwnerIndex=1986|IndexInSheet=23|OwnerPartId=-1|Location.X=1637|Location.Y=272|Color=8388608|FontID=1|IsHidden=T|Text=50 V|Name=Voltage Rating
|RECORD=41|OwnerIndex=1986|IndexInSheet=24|OwnerPartId=-1|Location.X=1637|Location.Y=272|Color=8388608|FontID=1|IsHidden=T|Text=0402|Name=Case\/Package
|RECORD=41|OwnerIndex=1986|IndexInSheet=25|OwnerPartId=-1|Location.X=1637|Location.Y=272|Color=8388608|FontID=1|IsHidden=T|Text=Surface Mount|Name=Mount
|RECORD=41|OwnerIndex=1986|IndexInSheet=26|OwnerPartId=-1|Location.X=1637|Location.Y=272|Color=8388608|FontID=8|IsHidden=T|Text=http://www.panasonic.com/|Name=ComponentLink1URL
|RECORD=41|OwnerIndex=1986|IndexInSheet=27|OwnerPartId=-1|Location.X=1637|Location.Y=272|Color=8388608|FontID=1|IsHidden=T|Text=-55 degC|Name=Min Operating Temperature
|RECORD=41|OwnerIndex=1986|IndexInSheet=28|OwnerPartId=-1|Location.X=1637|Location.Y=272|Color=8388608|FontID=1|IsHidden=T|Text=100 mW|Name=Power Rating
|RECORD=41|OwnerIndex=1986|IndexInSheet=29|OwnerPartId=-1|Location.X=1637|Location.Y=272|Color=8388608|FontID=1|IsHidden=T|Text=Cut Tape|Name=Packaging
|RECORD=41|OwnerIndex=1986|IndexInSheet=30|OwnerPartId=-1|Location.X=1637|Location.Y=272|Color=8388608|FontID=8|IsHidden=T|Text=http://industrial.panasonic.com/cdbs/www-data/pdf/RDA0000/AOA0000C86.pdf|Name=ComponentLink2URL
|RECORD=34|OwnerIndex=1986|IndexInSheet=-1|OwnerPartId=-1|Location.X=1640|Location.Y=220|Orientation=1|Color=8388608|FontID=2|Text=R56|Name=Designator|ReadOnlyState=1
|RECORD=41|OwnerIndex=1986|IndexInSheet=-1|OwnerPartId=-1|Location.X=1650|Location.Y=210|Orientation=1|Color=8388608|FontID=2|Text=DNI_4.7K_0402|Name=Comment
|RECORD=44|OwnerIndex=1986
|RECORD=45|OwnerIndex=2022|IndexInSheet=-1|Description=Chip Resistor, 2-Leads, Body 1.05x0.55mm, IPC High Density|UseComponentLibrary=T|ModelName=RESC1005X40X25LL05T05|ModelType=PCBLIB|DatafileCount=1|ModelDatafileEntity0=RESC1005X40X25LL05T05|ModelDatafileKind0=PCBLib|IsCurrent=T|DatalinksLocked=T|DatabaseDatalinksLocked=T
|RECORD=46|OwnerIndex=2023
|RECORD=48|OwnerIndex=2023
|RECORD=41|OwnerIndex=2025|IndexInSheet=-1|OwnerPartId=-1|Color=8388608|FontID=1|IsHidden=T|Text=2D|Name=Available Preview Images
|RECORD=45|OwnerIndex=2022|IndexInSheet=-1|Description=Chip Resistor, 2-Leads, Body 1.05x0.55mm, IPC Low Density|UseComponentLibrary=T|ModelName=RESC1005X40X25ML05T05|ModelType=PCBLIB|DatafileCount=1|ModelDatafileEntity0=RESC1005X40X25ML05T05|ModelDatafileKind0=PCBLib|DatalinksLocked=T|DatabaseDatalinksLocked=T
|RECORD=46|OwnerIndex=2027
|RECORD=48|OwnerIndex=2027
|RECORD=41|OwnerIndex=2029|IndexInSheet=-1|OwnerPartId=-1|Color=8388608|FontID=1|IsHidden=T|Text=2D|Name=Available Preview Images
|RECORD=45|OwnerIndex=2022|IndexInSheet=-1|Description=Chip Resistor, 2-Leads, Body 1.05x0.55mm, IPC Medium Density|UseComponentLibrary=T|ModelName=RESC1005X40X25NL05T05|ModelType=PCBLIB|DatafileCount=1|ModelDatafileEntity0=RESC1005X40X25NL05T05|ModelDatafileKind0=PCBLib|DatalinksLocked=T|DatabaseDatalinksLocked=T
|RECORD=46|OwnerIndex=2031
|RECORD=48|OwnerIndex=2031
|RECORD=41|OwnerIndex=2033|IndexInSheet=-1|OwnerPartId=-1|Color=8388608|FontID=1|IsHidden=T|Text=2D|Name=Available Preview Images
|RECORD=1|LibReference=RES-2|ComponentDescription=Chip Resistor, 4.7 KOhm, +/- 1%, 0.1 W, -55 to 155 degC, 0402 (1005 Metric), RoHS, Tape and Reel|PartCount=2|DisplayModeCount=1|IndexInSheet=204|OwnerPartId=-1|Location.X=1240|Location.Y=360|Orientation=2|CurrentPartId=1|LibraryPath=*|SourceLibraryName=Altium Content Vault|TargetFileName=*|AreaColor=11599871|Color=128|PartIDLocked=T|DesignItemId=CMP-2002-01154-4|AllPinCount=2
|RECORD=2|OwnerIndex=2035|OwnerPartId=1|FormalType=1|Electrical=4|PinConglomerate=34|PinLength=10|Location.X=1220|Location.Y=360|Name=2|Designator=2|PinPropagationDelay=0.000000E+000
|RECORD=2|OwnerIndex=2035|OwnerPartId=1|FormalType=1|Electrical=4|PinConglomerate=32|PinLength=10|Location.X=1240|Location.Y=360|Name=1|Designator=1|PinPropagationDelay=0.000000E+000
|RECORD=6|OwnerIndex=2035|IsNotAccesible=T|IndexInSheet=2|OwnerPartId=1|LineWidth=1|Color=16711680|LocationCount=10|X1=1220|Y1=360|X2=1224|Y2=360|X3=1225|Y3=362|X4=1227|Y4=358|X5=1229|Y5=362|X6=1231|Y6=358|X7=1233|Y7=362|X8=1235|Y8=358|X9=1236|Y9=360|X10=1240|Y10=360
|RECORD=41|OwnerIndex=2035|IndexInSheet=3|OwnerPartId=-1|Location.X=1208|Location.Y=363|Color=8388608|FontID=1|IsHidden=T|Text=0.35 mm|Name=Height
|RECORD=41|OwnerIndex=2035|IndexInSheet=4|OwnerPartId=-1|Location.X=1208|Location.Y=363|Color=8388608|FontID=1|IsHidden=T|Text=Surface Mount|Name=Mounting Technology
|RECORD=41|OwnerIndex=2035|IndexInSheet=5|OwnerPartId=-1|Location.X=1208|Location.Y=363|Color=8388608|FontID=1|IsHidden=T|Text=Yes|Name=REACH SVHC
|RECORD=41|OwnerIndex=2035|IndexInSheet=6|OwnerPartId=-1|Location.X=1208|Location.Y=363|Color=8388608|FontID=1|IsHidden=T|Text=4.7 KOhm|Name=Resistance
|RECORD=41|OwnerIndex=2035|IndexInSheet=7|OwnerPartId=-1|Location.X=1208|Location.Y=363|Color=8388608|FontID=1|IsHidden=T|Text=155 degC|Name=Max Operating Temperature
|RECORD=41|OwnerIndex=2035|IndexInSheet=8|OwnerPartId=-1|Location.X=1208|Location.Y=363|Color=8388608|FontID=1|IsHidden=T|Text=Manufacturer URL|Name=ComponentLink1Description
|RECORD=41|OwnerIndex=2035|IndexInSheet=9|OwnerPartId=-1|Location.X=1208|Location.Y=363|Color=8388608|FontID=1|IsHidden=T|Text=Datasheet|Name=ComponentLink2Description
|RECORD=41|OwnerIndex=2035|IndexInSheet=10|OwnerPartId=-1|Location.X=1208|Location.Y=363|Color=8388608|FontID=1|IsHidden=T|Text=2|Name=Pins
|RECORD=41|OwnerIndex=2035|IndexInSheet=11|OwnerPartId=-1|Location.X=1208|Location.Y=363|Color=8388608|FontID=1|IsHidden=T|Text=0402|Name=PackageReference
|RECORD=41|OwnerIndex=2035|IndexInSheet=12|OwnerPartId=-1|Location.X=1208|Location.Y=363|Color=8388608|FontID=1|IsHidden=T|Text=1%|Name=Tolerance
|RECORD=41|OwnerIndex=2035|IndexInSheet=13|OwnerPartId=-1|Location.X=1208|Location.Y=363|Color=8388608|FontID=1|IsHidden=T|Text=0402|Name=Case Code (Imperial)
|RECORD=41|OwnerIndex=2035|IndexInSheet=14|OwnerPartId=-1|Location.X=1208|Location.Y=363|Color=8388608|FontID=1|IsHidden=T|Text=1 mm|Name=Length
|RECORD=41|OwnerIndex=2035|IndexInSheet=15|OwnerPartId=-1|Location.X=1208|Location.Y=363|Color=8388608|FontID=1|IsHidden=T|Text=2-Pin Surface Mount Device, Body 1 x 0.5 mm|Name=PackageDescription
|RECORD=41|OwnerIndex=2035|IndexInSheet=16|OwnerPartId=-1|Location.X=1208|Location.Y=363|Color=8388608|FontID=1|IsHidden=T|Text=ERJ-2RKF4701X|Name=PartNumber
|RECORD=41|OwnerIndex=2035|IndexInSheet=17|OwnerPartId=-1|Location.X=1208|Location.Y=363|Color=8388608|FontID=1|IsHidden=T|Text=true|Name=RoHSCompliant
|RECORD=41|OwnerIndex=2035|IndexInSheet=18|OwnerPartId=-1|Location.X=1208|Location.Y=363|Color=8388608|FontID=1|IsHidden=T|Text=1|Name=Package Quantity
|RECORD=41|OwnerIndex=2035|IndexInSheet=19|OwnerPartId=-1|Location.X=1208|Location.Y=363|Color=8388608|FontID=1|IsHidden=T|Text=No|Name=Radiation Hardening
|RECORD=41|OwnerIndex=2035|IndexInSheet=20|OwnerPartId=-1|Location.X=1208|Location.Y=363|Color=8388608|FontID=1|IsHidden=T|Text=04/2015|Name=DatasheetVersion
|RECORD=41|OwnerIndex=2035|IndexInSheet=21|OwnerPartId=-1|Location.X=1208|Location.Y=363|Color=8388608|FontID=1|IsHidden=T|Text=0.5 mm|Name=Width
|RECORD=41|OwnerIndex=2035|IndexInSheet=22|OwnerPartId=-1|Location.X=1208|Location.Y=363|Color=8388608|FontID=1|IsHidden=T|Text=1005|Name=Case Code (Metric)
|RECORD=41|OwnerIndex=2035|IndexInSheet=23|OwnerPartId=-1|Location.X=1208|Location.Y=363|Color=8388608|FontID=1|IsHidden=T|Text=50 V|Name=Voltage Rating
|RECORD=41|OwnerIndex=2035|IndexInSheet=24|OwnerPartId=-1|Location.X=1208|Location.Y=363|Color=8388608|FontID=1|IsHidden=T|Text=0402|Name=Case\/Package
|RECORD=41|OwnerIndex=2035|IndexInSheet=25|OwnerPartId=-1|Location.X=1208|Location.Y=363|Color=8388608|FontID=1|IsHidden=T|Text=Surface Mount|Name=Mount
|RECORD=41|OwnerIndex=2035|IndexInSheet=26|OwnerPartId=-1|Location.X=1208|Location.Y=363|Color=8388608|FontID=8|IsHidden=T|Text=http://www.panasonic.com/|Name=ComponentLink1URL
|RECORD=41|OwnerIndex=2035|IndexInSheet=27|OwnerPartId=-1|Location.X=1208|Location.Y=363|Color=8388608|FontID=1|IsHidden=T|Text=-55 degC|Name=Min Operating Temperature
|RECORD=41|OwnerIndex=2035|IndexInSheet=28|OwnerPartId=-1|Location.X=1208|Location.Y=363|Color=8388608|FontID=1|IsHidden=T|Text=100 mW|Name=Power Rating
|RECORD=41|OwnerIndex=2035|IndexInSheet=29|OwnerPartId=-1|Location.X=1208|Location.Y=363|Color=8388608|FontID=1|IsHidden=T|Text=Cut Tape|Name=Packaging
|RECORD=41|OwnerIndex=2035|IndexInSheet=30|OwnerPartId=-1|Location.X=1208|Location.Y=363|Color=8388608|FontID=8|IsHidden=T|Text=http://industrial.panasonic.com/cdbs/www-data/pdf/RDA0000/AOA0000C86.pdf|Name=ComponentLink2URL
|RECORD=34|OwnerIndex=2035|IndexInSheet=-1|OwnerPartId=-1|Location.X=1219|Location.Y=363|Color=8388608|FontID=1|Text=R52|Name=Designator|ReadOnlyState=1
|RECORD=41|OwnerIndex=2035|IndexInSheet=-1|OwnerPartId=-1|Location.X=1219|Location.Y=347|Color=8388608|FontID=1|Text=4.7K_0402|Name=Comment
|RECORD=44|OwnerIndex=2035
|RECORD=45|OwnerIndex=2071|IndexInSheet=-1|Description=Chip Resistor, 2-Leads, Body 1.05x0.55mm, IPC High Density|UseComponentLibrary=T|ModelName=RESC1005X40X25LL05T05|ModelType=PCBLIB|DatafileCount=1|ModelDatafileEntity0=RESC1005X40X25LL05T05|ModelDatafileKind0=PCBLib|IsCurrent=T|DatalinksLocked=T|DatabaseDatalinksLocked=T
|RECORD=46|OwnerIndex=2072
|RECORD=48|OwnerIndex=2072
|RECORD=41|OwnerIndex=2074|IndexInSheet=-1|OwnerPartId=-1|Color=8388608|FontID=1|IsHidden=T|Text=2D|Name=Available Preview Images
|RECORD=45|OwnerIndex=2071|IndexInSheet=-1|Description=Chip Resistor, 2-Leads, Body 1.05x0.55mm, IPC Low Density|UseComponentLibrary=T|ModelName=RESC1005X40X25ML05T05|ModelType=PCBLIB|DatafileCount=1|ModelDatafileEntity0=RESC1005X40X25ML05T05|ModelDatafileKind0=PCBLib|DatalinksLocked=T|DatabaseDatalinksLocked=T
|RECORD=46|OwnerIndex=2076
|RECORD=48|OwnerIndex=2076
|RECORD=41|OwnerIndex=2078|IndexInSheet=-1|OwnerPartId=-1|Color=8388608|FontID=1|IsHidden=T|Text=2D|Name=Available Preview Images
|RECORD=45|OwnerIndex=2071|IndexInSheet=-1|Description=Chip Resistor, 2-Leads, Body 1.05x0.55mm, IPC Medium Density|UseComponentLibrary=T|ModelName=RESC1005X40X25NL05T05|ModelType=PCBLIB|DatafileCount=1|ModelDatafileEntity0=RESC1005X40X25NL05T05|ModelDatafileKind0=PCBLib|DatalinksLocked=T|DatabaseDatalinksLocked=T
|RECORD=46|OwnerIndex=2080
|RECORD=48|OwnerIndex=2080
|RECORD=41|OwnerIndex=2082|IndexInSheet=-1|OwnerPartId=-1|Color=8388608|FontID=1|IsHidden=T|Text=2D|Name=Available Preview Images
|RECORD=1|LibReference=RES-2|ComponentDescription=Chip Resistor, 4.7 KOhm, +/- 1%, 0.1 W, -55 to 155 degC, 0402 (1005 Metric), RoHS, Tape and Reel|PartCount=2|DisplayModeCount=1|IndexInSheet=205|OwnerPartId=-1|Location.X=1590|Location.Y=460|Orientation=2|CurrentPartId=1|LibraryPath=*|SourceLibraryName=Altium Content Vault|TargetFileName=*|AreaColor=11599871|Color=128|PartIDLocked=T|DesignItemId=CMP-2002-01154-4|AllPinCount=2
|RECORD=2|OwnerIndex=2084|OwnerPartId=1|FormalType=1|Electrical=4|PinConglomerate=34|PinLength=10|Location.X=1570|Location.Y=460|Name=2|Designator=2|PinPropagationDelay=0.000000E+000
|RECORD=2|OwnerIndex=2084|OwnerPartId=1|FormalType=1|Electrical=4|PinConglomerate=32|PinLength=10|Location.X=1590|Location.Y=460|Name=1|Designator=1|PinPropagationDelay=0.000000E+000
|RECORD=6|OwnerIndex=2084|IsNotAccesible=T|IndexInSheet=2|OwnerPartId=1|LineWidth=1|Color=16711680|LocationCount=10|X1=1570|Y1=460|X2=1574|Y2=460|X3=1575|Y3=462|X4=1577|Y4=458|X5=1579|Y5=462|X6=1581|Y6=458|X7=1583|Y7=462|X8=1585|Y8=458|X9=1586|Y9=460|X10=1590|Y10=460
|RECORD=41|OwnerIndex=2084|IndexInSheet=3|OwnerPartId=-1|Location.X=1558|Location.Y=463|Color=8388608|FontID=1|IsHidden=T|Text=0.35 mm|Name=Height
|RECORD=41|OwnerIndex=2084|IndexInSheet=4|OwnerPartId=-1|Location.X=1558|Location.Y=463|Color=8388608|FontID=1|IsHidden=T|Text=Surface Mount|Name=Mounting Technology
|RECORD=41|OwnerIndex=2084|IndexInSheet=5|OwnerPartId=-1|Location.X=1558|Location.Y=463|Color=8388608|FontID=1|IsHidden=T|Text=Yes|Name=REACH SVHC
|RECORD=41|OwnerIndex=2084|IndexInSheet=6|OwnerPartId=-1|Location.X=1558|Location.Y=463|Color=8388608|FontID=1|IsHidden=T|Text=4.7 KOhm|Name=Resistance
|RECORD=41|OwnerIndex=2084|IndexInSheet=7|OwnerPartId=-1|Location.X=1558|Location.Y=463|Color=8388608|FontID=1|IsHidden=T|Text=155 degC|Name=Max Operating Temperature
|RECORD=41|OwnerIndex=2084|IndexInSheet=8|OwnerPartId=-1|Location.X=1558|Location.Y=463|Color=8388608|FontID=1|IsHidden=T|Text=Manufacturer URL|Name=ComponentLink1Description
|RECORD=41|OwnerIndex=2084|IndexInSheet=9|OwnerPartId=-1|Location.X=1558|Location.Y=463|Color=8388608|FontID=1|IsHidden=T|Text=Datasheet|Name=ComponentLink2Description
|RECORD=41|OwnerIndex=2084|IndexInSheet=10|OwnerPartId=-1|Location.X=1558|Location.Y=463|Color=8388608|FontID=1|IsHidden=T|Text=2|Name=Pins
|RECORD=41|OwnerIndex=2084|IndexInSheet=11|OwnerPartId=-1|Location.X=1558|Location.Y=463|Color=8388608|FontID=1|IsHidden=T|Text=0402|Name=PackageReference
|RECORD=41|OwnerIndex=2084|IndexInSheet=12|OwnerPartId=-1|Location.X=1558|Location.Y=463|Color=8388608|FontID=1|IsHidden=T|Text=1%|Name=Tolerance
|RECORD=41|OwnerIndex=2084|IndexInSheet=13|OwnerPartId=-1|Location.X=1558|Location.Y=463|Color=8388608|FontID=1|IsHidden=T|Text=0402|Name=Case Code (Imperial)
|RECORD=41|OwnerIndex=2084|IndexInSheet=14|OwnerPartId=-1|Location.X=1558|Location.Y=463|Color=8388608|FontID=1|IsHidden=T|Text=1 mm|Name=Length
|RECORD=41|OwnerIndex=2084|IndexInSheet=15|OwnerPartId=-1|Location.X=1558|Location.Y=463|Color=8388608|FontID=1|IsHidden=T|Text=2-Pin Surface Mount Device, Body 1 x 0.5 mm|Name=PackageDescription
|RECORD=41|OwnerIndex=2084|IndexInSheet=16|OwnerPartId=-1|Location.X=1558|Location.Y=463|Color=8388608|FontID=1|IsHidden=T|Text=ERJ-2RKF4701X|Name=PartNumber
|RECORD=41|OwnerIndex=2084|IndexInSheet=17|OwnerPartId=-1|Location.X=1558|Location.Y=463|Color=8388608|FontID=1|IsHidden=T|Text=true|Name=RoHSCompliant
|RECORD=41|OwnerIndex=2084|IndexInSheet=18|OwnerPartId=-1|Location.X=1558|Location.Y=463|Color=8388608|FontID=1|IsHidden=T|Text=1|Name=Package Quantity
|RECORD=41|OwnerIndex=2084|IndexInSheet=19|OwnerPartId=-1|Location.X=1558|Location.Y=463|Color=8388608|FontID=1|IsHidden=T|Text=No|Name=Radiation Hardening
|RECORD=41|OwnerIndex=2084|IndexInSheet=20|OwnerPartId=-1|Location.X=1558|Location.Y=463|Color=8388608|FontID=1|IsHidden=T|Text=04/2015|Name=DatasheetVersion
|RECORD=41|OwnerIndex=2084|IndexInSheet=21|OwnerPartId=-1|Location.X=1558|Location.Y=463|Color=8388608|FontID=1|IsHidden=T|Text=0.5 mm|Name=Width
|RECORD=41|OwnerIndex=2084|IndexInSheet=22|OwnerPartId=-1|Location.X=1558|Location.Y=463|Color=8388608|FontID=1|IsHidden=T|Text=1005|Name=Case Code (Metric)
|RECORD=41|OwnerIndex=2084|IndexInSheet=23|OwnerPartId=-1|Location.X=1558|Location.Y=463|Color=8388608|FontID=1|IsHidden=T|Text=50 V|Name=Voltage Rating
|RECORD=41|OwnerIndex=2084|IndexInSheet=24|OwnerPartId=-1|Location.X=1558|Location.Y=463|Color=8388608|FontID=1|IsHidden=T|Text=0402|Name=Case\/Package
|RECORD=41|OwnerIndex=2084|IndexInSheet=25|OwnerPartId=-1|Location.X=1558|Location.Y=463|Color=8388608|FontID=1|IsHidden=T|Text=Surface Mount|Name=Mount
|RECORD=41|OwnerIndex=2084|IndexInSheet=26|OwnerPartId=-1|Location.X=1558|Location.Y=463|Color=8388608|FontID=8|IsHidden=T|Text=http://www.panasonic.com/|Name=ComponentLink1URL
|RECORD=41|OwnerIndex=2084|IndexInSheet=27|OwnerPartId=-1|Location.X=1558|Location.Y=463|Color=8388608|FontID=1|IsHidden=T|Text=-55 degC|Name=Min Operating Temperature
|RECORD=41|OwnerIndex=2084|IndexInSheet=28|OwnerPartId=-1|Location.X=1558|Location.Y=463|Color=8388608|FontID=1|IsHidden=T|Text=100 mW|Name=Power Rating
|RECORD=41|OwnerIndex=2084|IndexInSheet=29|OwnerPartId=-1|Location.X=1558|Location.Y=463|Color=8388608|FontID=1|IsHidden=T|Text=Cut Tape|Name=Packaging
|RECORD=41|OwnerIndex=2084|IndexInSheet=30|OwnerPartId=-1|Location.X=1558|Location.Y=463|Color=8388608|FontID=8|IsHidden=T|Text=http://industrial.panasonic.com/cdbs/www-data/pdf/RDA0000/AOA0000C86.pdf|Name=ComponentLink2URL
|RECORD=34|OwnerIndex=2084|IndexInSheet=-1|OwnerPartId=-1|Location.X=1569|Location.Y=463|Color=8388608|FontID=1|Text=R50|Name=Designator|ReadOnlyState=1
|RECORD=41|OwnerIndex=2084|IndexInSheet=-1|OwnerPartId=-1|Location.X=1569|Location.Y=447|Color=8388608|FontID=1|Text=4.7K_0402|Name=Comment
|RECORD=44|OwnerIndex=2084
|RECORD=45|OwnerIndex=2120|IndexInSheet=-1|Description=Chip Resistor, 2-Leads, Body 1.05x0.55mm, IPC High Density|UseComponentLibrary=T|ModelName=RESC1005X40X25LL05T05|ModelType=PCBLIB|DatafileCount=1|ModelDatafileEntity0=RESC1005X40X25LL05T05|ModelDatafileKind0=PCBLib|IsCurrent=T|DatalinksLocked=T|DatabaseDatalinksLocked=T
|RECORD=46|OwnerIndex=2121
|RECORD=48|OwnerIndex=2121
|RECORD=41|OwnerIndex=2123|IndexInSheet=-1|OwnerPartId=-1|Color=8388608|FontID=1|IsHidden=T|Text=2D|Name=Available Preview Images
|RECORD=45|OwnerIndex=2120|IndexInSheet=-1|Description=Chip Resistor, 2-Leads, Body 1.05x0.55mm, IPC Low Density|UseComponentLibrary=T|ModelName=RESC1005X40X25ML05T05|ModelType=PCBLIB|DatafileCount=1|ModelDatafileEntity0=RESC1005X40X25ML05T05|ModelDatafileKind0=PCBLib|DatalinksLocked=T|DatabaseDatalinksLocked=T
|RECORD=46|OwnerIndex=2125
|RECORD=48|OwnerIndex=2125
|RECORD=41|OwnerIndex=2127|IndexInSheet=-1|OwnerPartId=-1|Color=8388608|FontID=1|IsHidden=T|Text=2D|Name=Available Preview Images
|RECORD=45|OwnerIndex=2120|IndexInSheet=-1|Description=Chip Resistor, 2-Leads, Body 1.05x0.55mm, IPC Medium Density|UseComponentLibrary=T|ModelName=RESC1005X40X25NL05T05|ModelType=PCBLIB|DatafileCount=1|ModelDatafileEntity0=RESC1005X40X25NL05T05|ModelDatafileKind0=PCBLib|DatalinksLocked=T|DatabaseDatalinksLocked=T
|RECORD=46|OwnerIndex=2129
|RECORD=48|OwnerIndex=2129
|RECORD=41|OwnerIndex=2131|IndexInSheet=-1|OwnerPartId=-1|Color=8388608|FontID=1|IsHidden=T|Text=2D|Name=Available Preview Images
|RECORD=1|LibReference=RES-2|ComponentDescription=Chip Resistor, 4.7 KOhm, +/- 1%, 0.1 W, -55 to 155 degC, 0402 (1005 Metric), RoHS, Tape and Reel|PartCount=2|DisplayModeCount=1|IndexInSheet=206|OwnerPartId=-1|Location.X=1550|Location.Y=430|Orientation=2|CurrentPartId=1|LibraryPath=*|SourceLibraryName=Altium Content Vault|TargetFileName=*|AreaColor=11599871|Color=128|PartIDLocked=T|DesignItemId=CMP-2002-01154-4|AllPinCount=2
|RECORD=2|OwnerIndex=2133|OwnerPartId=1|FormalType=1|Electrical=4|PinConglomerate=34|PinLength=10|Location.X=1530|Location.Y=430|Name=2|Designator=2|PinPropagationDelay=0.000000E+000
|RECORD=2|OwnerIndex=2133|OwnerPartId=1|FormalType=1|Electrical=4|PinConglomerate=32|PinLength=10|Location.X=1550|Location.Y=430|Name=1|Designator=1|PinPropagationDelay=0.000000E+000
|RECORD=6|OwnerIndex=2133|IsNotAccesible=T|IndexInSheet=2|OwnerPartId=1|LineWidth=1|Color=16711680|LocationCount=10|X1=1530|Y1=430|X2=1534|Y2=430|X3=1535|Y3=432|X4=1537|Y4=428|X5=1539|Y5=432|X6=1541|Y6=428|X7=1543|Y7=432|X8=1545|Y8=428|X9=1546|Y9=430|X10=1550|Y10=430
|RECORD=41|OwnerIndex=2133|IndexInSheet=3|OwnerPartId=-1|Location.X=1518|Location.Y=433|Color=8388608|FontID=1|IsHidden=T|Text=0.35 mm|Name=Height
|RECORD=41|OwnerIndex=2133|IndexInSheet=4|OwnerPartId=-1|Location.X=1518|Location.Y=433|Color=8388608|FontID=1|IsHidden=T|Text=Surface Mount|Name=Mounting Technology
|RECORD=41|OwnerIndex=2133|IndexInSheet=5|OwnerPartId=-1|Location.X=1518|Location.Y=433|Color=8388608|FontID=1|IsHidden=T|Text=Yes|Name=REACH SVHC
|RECORD=41|OwnerIndex=2133|IndexInSheet=6|OwnerPartId=-1|Location.X=1518|Location.Y=433|Color=8388608|FontID=1|IsHidden=T|Text=4.7 KOhm|Name=Resistance
|RECORD=41|OwnerIndex=2133|IndexInSheet=7|OwnerPartId=-1|Location.X=1518|Location.Y=433|Color=8388608|FontID=1|IsHidden=T|Text=155 degC|Name=Max Operating Temperature
|RECORD=41|OwnerIndex=2133|IndexInSheet=8|OwnerPartId=-1|Location.X=1518|Location.Y=433|Color=8388608|FontID=1|IsHidden=T|Text=Manufacturer URL|Name=ComponentLink1Description
|RECORD=41|OwnerIndex=2133|IndexInSheet=9|OwnerPartId=-1|Location.X=1518|Location.Y=433|Color=8388608|FontID=1|IsHidden=T|Text=Datasheet|Name=ComponentLink2Description
|RECORD=41|OwnerIndex=2133|IndexInSheet=10|OwnerPartId=-1|Location.X=1518|Location.Y=433|Color=8388608|FontID=1|IsHidden=T|Text=2|Name=Pins
|RECORD=41|OwnerIndex=2133|IndexInSheet=11|OwnerPartId=-1|Location.X=1518|Location.Y=433|Color=8388608|FontID=1|IsHidden=T|Text=0402|Name=PackageReference
|RECORD=41|OwnerIndex=2133|IndexInSheet=12|OwnerPartId=-1|Location.X=1518|Location.Y=433|Color=8388608|FontID=1|IsHidden=T|Text=1%|Name=Tolerance
|RECORD=41|OwnerIndex=2133|IndexInSheet=13|OwnerPartId=-1|Location.X=1518|Location.Y=433|Color=8388608|FontID=1|IsHidden=T|Text=0402|Name=Case Code (Imperial)
|RECORD=41|OwnerIndex=2133|IndexInSheet=14|OwnerPartId=-1|Location.X=1518|Location.Y=433|Color=8388608|FontID=1|IsHidden=T|Text=1 mm|Name=Length
|RECORD=41|OwnerIndex=2133|IndexInSheet=15|OwnerPartId=-1|Location.X=1518|Location.Y=433|Color=8388608|FontID=1|IsHidden=T|Text=2-Pin Surface Mount Device, Body 1 x 0.5 mm|Name=PackageDescription
|RECORD=41|OwnerIndex=2133|IndexInSheet=16|OwnerPartId=-1|Location.X=1518|Location.Y=433|Color=8388608|FontID=1|IsHidden=T|Text=ERJ-2RKF4701X|Name=PartNumber
|RECORD=41|OwnerIndex=2133|IndexInSheet=17|OwnerPartId=-1|Location.X=1518|Location.Y=433|Color=8388608|FontID=1|IsHidden=T|Text=true|Name=RoHSCompliant
|RECORD=41|OwnerIndex=2133|IndexInSheet=18|OwnerPartId=-1|Location.X=1518|Location.Y=433|Color=8388608|FontID=1|IsHidden=T|Text=1|Name=Package Quantity
|RECORD=41|OwnerIndex=2133|IndexInSheet=19|OwnerPartId=-1|Location.X=1518|Location.Y=433|Color=8388608|FontID=1|IsHidden=T|Text=No|Name=Radiation Hardening
|RECORD=41|OwnerIndex=2133|IndexInSheet=20|OwnerPartId=-1|Location.X=1518|Location.Y=433|Color=8388608|FontID=1|IsHidden=T|Text=04/2015|Name=DatasheetVersion
|RECORD=41|OwnerIndex=2133|IndexInSheet=21|OwnerPartId=-1|Location.X=1518|Location.Y=433|Color=8388608|FontID=1|IsHidden=T|Text=0.5 mm|Name=Width
|RECORD=41|OwnerIndex=2133|IndexInSheet=22|OwnerPartId=-1|Location.X=1518|Location.Y=433|Color=8388608|FontID=1|IsHidden=T|Text=1005|Name=Case Code (Metric)
|RECORD=41|OwnerIndex=2133|IndexInSheet=23|OwnerPartId=-1|Location.X=1518|Location.Y=433|Color=8388608|FontID=1|IsHidden=T|Text=50 V|Name=Voltage Rating
|RECORD=41|OwnerIndex=2133|IndexInSheet=24|OwnerPartId=-1|Location.X=1518|Location.Y=433|Color=8388608|FontID=1|IsHidden=T|Text=0402|Name=Case\/Package
|RECORD=41|OwnerIndex=2133|IndexInSheet=25|OwnerPartId=-1|Location.X=1518|Location.Y=433|Color=8388608|FontID=1|IsHidden=T|Text=Surface Mount|Name=Mount
|RECORD=41|OwnerIndex=2133|IndexInSheet=26|OwnerPartId=-1|Location.X=1518|Location.Y=433|Color=8388608|FontID=8|IsHidden=T|Text=http://www.panasonic.com/|Name=ComponentLink1URL
|RECORD=41|OwnerIndex=2133|IndexInSheet=27|OwnerPartId=-1|Location.X=1518|Location.Y=433|Color=8388608|FontID=1|IsHidden=T|Text=-55 degC|Name=Min Operating Temperature
|RECORD=41|OwnerIndex=2133|IndexInSheet=28|OwnerPartId=-1|Location.X=1518|Location.Y=433|Color=8388608|FontID=1|IsHidden=T|Text=100 mW|Name=Power Rating
|RECORD=41|OwnerIndex=2133|IndexInSheet=29|OwnerPartId=-1|Location.X=1518|Location.Y=433|Color=8388608|FontID=1|IsHidden=T|Text=Cut Tape|Name=Packaging
|RECORD=41|OwnerIndex=2133|IndexInSheet=30|OwnerPartId=-1|Location.X=1518|Location.Y=433|Color=8388608|FontID=8|IsHidden=T|Text=http://industrial.panasonic.com/cdbs/www-data/pdf/RDA0000/AOA0000C86.pdf|Name=ComponentLink2URL
|RECORD=34|OwnerIndex=2133|IndexInSheet=-1|OwnerPartId=-1|Location.X=1529|Location.Y=433|Color=8388608|FontID=1|Text=R51|Name=Designator|ReadOnlyState=1
|RECORD=41|OwnerIndex=2133|IndexInSheet=-1|OwnerPartId=-1|Location.X=1529|Location.Y=417|Color=8388608|FontID=1|Text=4.7K_0402|Name=Comment
|RECORD=44|OwnerIndex=2133
|RECORD=45|OwnerIndex=2169|IndexInSheet=-1|Description=Chip Resistor, 2-Leads, Body 1.05x0.55mm, IPC High Density|UseComponentLibrary=T|ModelName=RESC1005X40X25LL05T05|ModelType=PCBLIB|DatafileCount=1|ModelDatafileEntity0=RESC1005X40X25LL05T05|ModelDatafileKind0=PCBLib|IsCurrent=T|DatalinksLocked=T|DatabaseDatalinksLocked=T
|RECORD=46|OwnerIndex=2170
|RECORD=48|OwnerIndex=2170
|RECORD=41|OwnerIndex=2172|IndexInSheet=-1|OwnerPartId=-1|Color=8388608|FontID=1|IsHidden=T|Text=2D|Name=Available Preview Images
|RECORD=45|OwnerIndex=2169|IndexInSheet=-1|Description=Chip Resistor, 2-Leads, Body 1.05x0.55mm, IPC Low Density|UseComponentLibrary=T|ModelName=RESC1005X40X25ML05T05|ModelType=PCBLIB|DatafileCount=1|ModelDatafileEntity0=RESC1005X40X25ML05T05|ModelDatafileKind0=PCBLib|DatalinksLocked=T|DatabaseDatalinksLocked=T
|RECORD=46|OwnerIndex=2174
|RECORD=48|OwnerIndex=2174
|RECORD=41|OwnerIndex=2176|IndexInSheet=-1|OwnerPartId=-1|Color=8388608|FontID=1|IsHidden=T|Text=2D|Name=Available Preview Images
|RECORD=45|OwnerIndex=2169|IndexInSheet=-1|Description=Chip Resistor, 2-Leads, Body 1.05x0.55mm, IPC Medium Density|UseComponentLibrary=T|ModelName=RESC1005X40X25NL05T05|ModelType=PCBLIB|DatafileCount=1|ModelDatafileEntity0=RESC1005X40X25NL05T05|ModelDatafileKind0=PCBLib|DatalinksLocked=T|DatabaseDatalinksLocked=T
|RECORD=46|OwnerIndex=2178
|RECORD=48|OwnerIndex=2178
|RECORD=41|OwnerIndex=2180|IndexInSheet=-1|OwnerPartId=-1|Color=8388608|FontID=1|IsHidden=T|Text=2D|Name=Available Preview Images
|RECORD=1|LibReference=RES-2|ComponentDescription=Chip Resistor, 4.7 KOhm, +/- 1%, 0.1 W, -55 to 155 degC, 0402 (1005 Metric), RoHS, Tape and Reel|PartCount=2|DisplayModeCount=1|IndexInSheet=207|OwnerPartId=-1|Location.X=1540|Location.Y=270|Orientation=2|CurrentPartId=1|LibraryPath=*|SourceLibraryName=Altium Content Vault|TargetFileName=*|AreaColor=11599871|Color=128|PartIDLocked=T|DesignItemId=CMP-2002-01154-4|AllPinCount=2
|RECORD=2|OwnerIndex=2182|OwnerPartId=1|FormalType=1|Electrical=4|PinConglomerate=34|PinLength=10|Location.X=1520|Location.Y=270|Name=2|Designator=2|PinPropagationDelay=0.000000E+000
|RECORD=2|OwnerIndex=2182|OwnerPartId=1|FormalType=1|Electrical=4|PinConglomerate=32|PinLength=10|Location.X=1540|Location.Y=270|Name=1|Designator=1|PinPropagationDelay=0.000000E+000
|RECORD=6|OwnerIndex=2182|IsNotAccesible=T|IndexInSheet=2|OwnerPartId=1|LineWidth=1|Color=16711680|LocationCount=10|X1=1520|Y1=270|X2=1524|Y2=270|X3=1525|Y3=272|X4=1527|Y4=268|X5=1529|Y5=272|X6=1531|Y6=268|X7=1533|Y7=272|X8=1535|Y8=268|X9=1536|Y9=270|X10=1540|Y10=270
|RECORD=41|OwnerIndex=2182|IndexInSheet=3|OwnerPartId=-1|Location.X=1508|Location.Y=273|Color=8388608|FontID=1|IsHidden=T|Text=0.35 mm|Name=Height
|RECORD=41|OwnerIndex=2182|IndexInSheet=4|OwnerPartId=-1|Location.X=1508|Location.Y=273|Color=8388608|FontID=1|IsHidden=T|Text=Surface Mount|Name=Mounting Technology
|RECORD=41|OwnerIndex=2182|IndexInSheet=5|OwnerPartId=-1|Location.X=1508|Location.Y=273|Color=8388608|FontID=1|IsHidden=T|Text=Yes|Name=REACH SVHC
|RECORD=41|OwnerIndex=2182|IndexInSheet=6|OwnerPartId=-1|Location.X=1508|Location.Y=273|Color=8388608|FontID=1|IsHidden=T|Text=4.7 KOhm|Name=Resistance
|RECORD=41|OwnerIndex=2182|IndexInSheet=7|OwnerPartId=-1|Location.X=1508|Location.Y=273|Color=8388608|FontID=1|IsHidden=T|Text=155 degC|Name=Max Operating Temperature
|RECORD=41|OwnerIndex=2182|IndexInSheet=8|OwnerPartId=-1|Location.X=1508|Location.Y=273|Color=8388608|FontID=1|IsHidden=T|Text=Manufacturer URL|Name=ComponentLink1Description
|RECORD=41|OwnerIndex=2182|IndexInSheet=9|OwnerPartId=-1|Location.X=1508|Location.Y=273|Color=8388608|FontID=1|IsHidden=T|Text=Datasheet|Name=ComponentLink2Description
|RECORD=41|OwnerIndex=2182|IndexInSheet=10|OwnerPartId=-1|Location.X=1508|Location.Y=273|Color=8388608|FontID=1|IsHidden=T|Text=2|Name=Pins
|RECORD=41|OwnerIndex=2182|IndexInSheet=11|OwnerPartId=-1|Location.X=1508|Location.Y=273|Color=8388608|FontID=1|IsHidden=T|Text=0402|Name=PackageReference
|RECORD=41|OwnerIndex=2182|IndexInSheet=12|OwnerPartId=-1|Location.X=1508|Location.Y=273|Color=8388608|FontID=1|IsHidden=T|Text=1%|Name=Tolerance
|RECORD=41|OwnerIndex=2182|IndexInSheet=13|OwnerPartId=-1|Location.X=1508|Location.Y=273|Color=8388608|FontID=1|IsHidden=T|Text=0402|Name=Case Code (Imperial)
|RECORD=41|OwnerIndex=2182|IndexInSheet=14|OwnerPartId=-1|Location.X=1508|Location.Y=273|Color=8388608|FontID=1|IsHidden=T|Text=1 mm|Name=Length
|RECORD=41|OwnerIndex=2182|IndexInSheet=15|OwnerPartId=-1|Location.X=1508|Location.Y=273|Color=8388608|FontID=1|IsHidden=T|Text=2-Pin Surface Mount Device, Body 1 x 0.5 mm|Name=PackageDescription
|RECORD=41|OwnerIndex=2182|IndexInSheet=16|OwnerPartId=-1|Location.X=1508|Location.Y=273|Color=8388608|FontID=1|IsHidden=T|Text=ERJ-2RKF4701X|Name=PartNumber
|RECORD=41|OwnerIndex=2182|IndexInSheet=17|OwnerPartId=-1|Location.X=1508|Location.Y=273|Color=8388608|FontID=1|IsHidden=T|Text=true|Name=RoHSCompliant
|RECORD=41|OwnerIndex=2182|IndexInSheet=18|OwnerPartId=-1|Location.X=1508|Location.Y=273|Color=8388608|FontID=1|IsHidden=T|Text=1|Name=Package Quantity
|RECORD=41|OwnerIndex=2182|IndexInSheet=19|OwnerPartId=-1|Location.X=1508|Location.Y=273|Color=8388608|FontID=1|IsHidden=T|Text=No|Name=Radiation Hardening
|RECORD=41|OwnerIndex=2182|IndexInSheet=20|OwnerPartId=-1|Location.X=1508|Location.Y=273|Color=8388608|FontID=1|IsHidden=T|Text=04/2015|Name=DatasheetVersion
|RECORD=41|OwnerIndex=2182|IndexInSheet=21|OwnerPartId=-1|Location.X=1508|Location.Y=273|Color=8388608|FontID=1|IsHidden=T|Text=0.5 mm|Name=Width
|RECORD=41|OwnerIndex=2182|IndexInSheet=22|OwnerPartId=-1|Location.X=1508|Location.Y=273|Color=8388608|FontID=1|IsHidden=T|Text=1005|Name=Case Code (Metric)
|RECORD=41|OwnerIndex=2182|IndexInSheet=23|OwnerPartId=-1|Location.X=1508|Location.Y=273|Color=8388608|FontID=1|IsHidden=T|Text=50 V|Name=Voltage Rating
|RECORD=41|OwnerIndex=2182|IndexInSheet=24|OwnerPartId=-1|Location.X=1508|Location.Y=273|Color=8388608|FontID=1|IsHidden=T|Text=0402|Name=Case\/Package
|RECORD=41|OwnerIndex=2182|IndexInSheet=25|OwnerPartId=-1|Location.X=1508|Location.Y=273|Color=8388608|FontID=1|IsHidden=T|Text=Surface Mount|Name=Mount
|RECORD=41|OwnerIndex=2182|IndexInSheet=26|OwnerPartId=-1|Location.X=1508|Location.Y=273|Color=8388608|FontID=8|IsHidden=T|Text=http://www.panasonic.com/|Name=ComponentLink1URL
|RECORD=41|OwnerIndex=2182|IndexInSheet=27|OwnerPartId=-1|Location.X=1508|Location.Y=273|Color=8388608|FontID=1|IsHidden=T|Text=-55 degC|Name=Min Operating Temperature
|RECORD=41|OwnerIndex=2182|IndexInSheet=28|OwnerPartId=-1|Location.X=1508|Location.Y=273|Color=8388608|FontID=1|IsHidden=T|Text=100 mW|Name=Power Rating
|RECORD=41|OwnerIndex=2182|IndexInSheet=29|OwnerPartId=-1|Location.X=1508|Location.Y=273|Color=8388608|FontID=1|IsHidden=T|Text=Cut Tape|Name=Packaging
|RECORD=41|OwnerIndex=2182|IndexInSheet=30|OwnerPartId=-1|Location.X=1508|Location.Y=273|Color=8388608|FontID=8|IsHidden=T|Text=http://industrial.panasonic.com/cdbs/www-data/pdf/RDA0000/AOA0000C86.pdf|Name=ComponentLink2URL
|RECORD=34|OwnerIndex=2182|IndexInSheet=-1|OwnerPartId=-1|Location.X=1519|Location.Y=273|Color=8388608|FontID=1|Text=R55|Name=Designator|ReadOnlyState=1
|RECORD=41|OwnerIndex=2182|IndexInSheet=-1|OwnerPartId=-1|Location.X=1519|Location.Y=257|Color=8388608|FontID=1|Text=4.7K_0402|Name=Comment
|RECORD=44|OwnerIndex=2182
|RECORD=45|OwnerIndex=2218|IndexInSheet=-1|Description=Chip Resistor, 2-Leads, Body 1.05x0.55mm, IPC High Density|UseComponentLibrary=T|ModelName=RESC1005X40X25LL05T05|ModelType=PCBLIB|DatafileCount=1|ModelDatafileEntity0=RESC1005X40X25LL05T05|ModelDatafileKind0=PCBLib|IsCurrent=T|DatalinksLocked=T|DatabaseDatalinksLocked=T
|RECORD=46|OwnerIndex=2219
|RECORD=48|OwnerIndex=2219
|RECORD=41|OwnerIndex=2221|IndexInSheet=-1|OwnerPartId=-1|Color=8388608|FontID=1|IsHidden=T|Text=2D|Name=Available Preview Images
|RECORD=45|OwnerIndex=2218|IndexInSheet=-1|Description=Chip Resistor, 2-Leads, Body 1.05x0.55mm, IPC Low Density|UseComponentLibrary=T|ModelName=RESC1005X40X25ML05T05|ModelType=PCBLIB|DatafileCount=1|ModelDatafileEntity0=RESC1005X40X25ML05T05|ModelDatafileKind0=PCBLib|DatalinksLocked=T|DatabaseDatalinksLocked=T
|RECORD=46|OwnerIndex=2223
|RECORD=48|OwnerIndex=2223
|RECORD=41|OwnerIndex=2225|IndexInSheet=-1|OwnerPartId=-1|Color=8388608|FontID=1|IsHidden=T|Text=2D|Name=Available Preview Images
|RECORD=45|OwnerIndex=2218|IndexInSheet=-1|Description=Chip Resistor, 2-Leads, Body 1.05x0.55mm, IPC Medium Density|UseComponentLibrary=T|ModelName=RESC1005X40X25NL05T05|ModelType=PCBLIB|DatafileCount=1|ModelDatafileEntity0=RESC1005X40X25NL05T05|ModelDatafileKind0=PCBLib|DatalinksLocked=T|DatabaseDatalinksLocked=T
|RECORD=46|OwnerIndex=2227
|RECORD=48|OwnerIndex=2227
|RECORD=41|OwnerIndex=2229|IndexInSheet=-1|OwnerPartId=-1|Color=8388608|FontID=1|IsHidden=T|Text=2D|Name=Available Preview Images
|RECORD=1|LibReference=CAP|PartCount=2|DisplayModeCount=2|IndexInSheet=208|OwnerPartId=-1|Location.X=1110|Location.Y=300|Orientation=1|CurrentPartId=1|SourceLibraryName=Altium Content Vault|TargetFileName=*|AreaColor=11599871|Color=128|PartIDLocked=F|DesignItemId=CMP-2008-00031-1|AllPinCount=2
|RECORD=2|OwnerIndex=2231|OwnerPartId=1|OwnerPartDisplayMode=1|FormalType=1|Electrical=4|PinConglomerate=35|PinLength=10|Location.X=1120|Location.Y=300|Name=1|Designator=1|PinPropagationDelay=0.000000E+000
|RECORD=2|OwnerIndex=2231|OwnerPartId=1|OwnerPartDisplayMode=1|FormalType=1|Electrical=4|PinConglomerate=33|PinLength=10|Location.X=1120|Location.Y=310|Name=2|Designator=2|PinPropagationDelay=0.000000E+000
|RECORD=13|OwnerIndex=2231|IsNotAccesible=T|IndexInSheet=2|OwnerPartId=1|OwnerPartDisplayMode=1|Location.X=1128|Location.Y=300|Corner.X=1112|Corner.Y=300|LineWidth=1|Color=16711680
|RECORD=13|OwnerIndex=2231|IsNotAccesible=T|IndexInSheet=3|OwnerPartId=1|OwnerPartDisplayMode=1|Location.X=1120|Location.Y=304|Corner.X=1120|Corner.Y=310|LineWidth=1|Color=16711680
|RECORD=12|OwnerIndex=2231|IsNotAccesible=T|IndexInSheet=4|OwnerPartId=1|OwnerPartDisplayMode=1|Location.X=1120|Location.Y=320|Radius=16|LineWidth=1|StartAngle=241.000|EndAngle=270.000|Color=16711680
|RECORD=12|OwnerIndex=2231|IsNotAccesible=T|IndexInSheet=5|OwnerPartId=1|OwnerPartDisplayMode=1|Location.X=1120|Location.Y=320|Radius=16|LineWidth=1|StartAngle=270.000|EndAngle=299.000|Color=16711680
|RECORD=2|OwnerIndex=2231|OwnerPartId=1|FormalType=1|Electrical=4|PinConglomerate=35|PinLength=10|Location.X=1120|Location.Y=300|Name=1|Designator=1|PinPropagationDelay=0.000000E+000
|RECORD=2|OwnerIndex=2231|OwnerPartId=1|FormalType=1|Electrical=4|PinConglomerate=33|PinLength=10|Location.X=1120|Location.Y=310|Name=2|Designator=2|PinPropagationDelay=0.000000E+000
|RECORD=13|OwnerIndex=2231|IsNotAccesible=T|IndexInSheet=8|OwnerPartId=1|Location.X=1112|Location.Y=307|Corner.X=1128|Corner.Y=307|LineWidth=1|Color=16711680
|RECORD=13|OwnerIndex=2231|IsNotAccesible=T|IndexInSheet=9|OwnerPartId=1|Location.X=1128|Location.Y=303|Corner.X=1112|Corner.Y=303|LineWidth=1|Color=16711680
|RECORD=6|OwnerIndex=2231|IsNotAccesible=T|IndexInSheet=10|OwnerPartId=1|LineWidth=1|Color=16711680|LocationCount=2|X1=1120|Y1=300|X2=1120|Y2=303
|RECORD=6|OwnerIndex=2231|IsNotAccesible=T|IndexInSheet=11|OwnerPartId=1|LineWidth=1|Color=16711680|LocationCount=2|X1=1120|Y1=310|X2=1120|Y2=307
|RECORD=41|OwnerIndex=2231|IndexInSheet=12|OwnerPartId=-1|Location.X=1111|Location.Y=322|Color=8388608|FontID=1|IsHidden=T|Text=LD02YD104KAB2A|Name=Part Number
|RECORD=41|OwnerIndex=2231|IndexInSheet=13|OwnerPartId=-1|Location.X=1111|Location.Y=322|Color=8388608|FontID=1|IsHidden=T|Text=AVX Interconnect / Elco|Name=Manufacturer
|RECORD=34|OwnerIndex=2231|IndexInSheet=-1|OwnerPartId=-1|Location.X=1120|Location.Y=280|Orientation=1|Color=8388608|FontID=2|Text=C66|Name=Designator|ReadOnlyState=1
|RECORD=41|OwnerIndex=2231|IndexInSheet=-1|OwnerPartId=-1|Location.X=1130|Location.Y=250|Orientation=1|Color=8388608|FontID=2|Text=0.1uF_0402|Name=Comment
|RECORD=44|OwnerIndex=2231
|RECORD=45|OwnerIndex=2252|IndexInSheet=-1|Description=Chip Capacitor, 2-Leads, Body 1.00x0.50mm, IPC Medium Density|UseComponentLibrary=T|ModelName=CAPC1005X56X25NL10T15|ModelType=PCBLIB|DatafileCount=1|ModelDatafileEntity0=CAPC1005X56X25NL10T15|ModelDatafileKind0=PCBLib|IsCurrent=T|DatalinksLocked=T|DatabaseDatalinksLocked=T
|RECORD=46|OwnerIndex=2253
|RECORD=48|OwnerIndex=2253
|RECORD=41|OwnerIndex=2255|IndexInSheet=-1|OwnerPartId=-1|Color=8388608|FontID=1|IsHidden=T|Text=2D|Name=Available Preview Images
|RECORD=45|OwnerIndex=2252|IndexInSheet=-1|Description=Chip Capacitor, 2-Leads, Body 1.00x0.50mm, IPC High Density|UseComponentLibrary=T|ModelName=CAPC1005X56X25LL10T15|ModelType=PCBLIB|DatafileCount=1|ModelDatafileEntity0=CAPC1005X56X25LL10T15|ModelDatafileKind0=PCBLib|DatalinksLocked=T|DatabaseDatalinksLocked=T
|RECORD=46|OwnerIndex=2257
|RECORD=48|OwnerIndex=2257
|RECORD=41|OwnerIndex=2259|IndexInSheet=-1|OwnerPartId=-1|Color=8388608|FontID=1|IsHidden=T|Text=2D|Name=Available Preview Images
|RECORD=45|OwnerIndex=2252|IndexInSheet=-1|Description=Chip Capacitor, 2-Leads, Body 1.00x0.50mm, IPC Low Density|UseComponentLibrary=T|ModelName=CAPC1005X56X25ML10T15|ModelType=PCBLIB|DatafileCount=1|ModelDatafileEntity0=CAPC1005X56X25ML10T15|ModelDatafileKind0=PCBLib|DatalinksLocked=T|DatabaseDatalinksLocked=T
|RECORD=46|OwnerIndex=2261
|RECORD=48|OwnerIndex=2261
|RECORD=41|OwnerIndex=2263|IndexInSheet=-1|OwnerPartId=-1|Color=8388608|FontID=1|IsHidden=T|Text=2D|Name=Available Preview Images
|RECORD=1|LibReference=CAP|PartCount=2|DisplayModeCount=2|IndexInSheet=209|OwnerPartId=-1|Location.X=1150|Location.Y=300|Orientation=1|CurrentPartId=1|SourceLibraryName=Altium Content Vault|TargetFileName=*|AreaColor=11599871|Color=128|PartIDLocked=F|DesignItemId=CMP-2008-00031-1|AllPinCount=2
|RECORD=2|OwnerIndex=2265|OwnerPartId=1|OwnerPartDisplayMode=1|FormalType=1|Electrical=4|PinConglomerate=35|PinLength=10|Location.X=1160|Location.Y=300|Name=1|Designator=1|PinPropagationDelay=0.000000E+000
|RECORD=2|OwnerIndex=2265|OwnerPartId=1|OwnerPartDisplayMode=1|FormalType=1|Electrical=4|PinConglomerate=33|PinLength=10|Location.X=1160|Location.Y=310|Name=2|Designator=2|PinPropagationDelay=0.000000E+000
|RECORD=13|OwnerIndex=2265|IsNotAccesible=T|IndexInSheet=2|OwnerPartId=1|OwnerPartDisplayMode=1|Location.X=1168|Location.Y=300|Corner.X=1152|Corner.Y=300|LineWidth=1|Color=16711680
|RECORD=13|OwnerIndex=2265|IsNotAccesible=T|IndexInSheet=3|OwnerPartId=1|OwnerPartDisplayMode=1|Location.X=1160|Location.Y=304|Corner.X=1160|Corner.Y=310|LineWidth=1|Color=16711680
|RECORD=12|OwnerIndex=2265|IsNotAccesible=T|IndexInSheet=4|OwnerPartId=1|OwnerPartDisplayMode=1|Location.X=1160|Location.Y=320|Radius=16|LineWidth=1|StartAngle=241.000|EndAngle=270.000|Color=16711680
|RECORD=12|OwnerIndex=2265|IsNotAccesible=T|IndexInSheet=5|OwnerPartId=1|OwnerPartDisplayMode=1|Location.X=1160|Location.Y=320|Radius=16|LineWidth=1|StartAngle=270.000|EndAngle=299.000|Color=16711680
|RECORD=2|OwnerIndex=2265|OwnerPartId=1|FormalType=1|Electrical=4|PinConglomerate=35|PinLength=10|Location.X=1160|Location.Y=300|Name=1|Designator=1|PinPropagationDelay=0.000000E+000
|RECORD=2|OwnerIndex=2265|OwnerPartId=1|FormalType=1|Electrical=4|PinConglomerate=33|PinLength=10|Location.X=1160|Location.Y=310|Name=2|Designator=2|PinPropagationDelay=0.000000E+000
|RECORD=13|OwnerIndex=2265|IsNotAccesible=T|IndexInSheet=8|OwnerPartId=1|Location.X=1152|Location.Y=307|Corner.X=1168|Corner.Y=307|LineWidth=1|Color=16711680
|RECORD=13|OwnerIndex=2265|IsNotAccesible=T|IndexInSheet=9|OwnerPartId=1|Location.X=1168|Location.Y=303|Corner.X=1152|Corner.Y=303|LineWidth=1|Color=16711680
|RECORD=6|OwnerIndex=2265|IsNotAccesible=T|IndexInSheet=10|OwnerPartId=1|LineWidth=1|Color=16711680|LocationCount=2|X1=1160|Y1=300|X2=1160|Y2=303
|RECORD=6|OwnerIndex=2265|IsNotAccesible=T|IndexInSheet=11|OwnerPartId=1|LineWidth=1|Color=16711680|LocationCount=2|X1=1160|Y1=310|X2=1160|Y2=307
|RECORD=41|OwnerIndex=2265|IndexInSheet=12|OwnerPartId=-1|Location.X=1151|Location.Y=322|Color=8388608|FontID=1|IsHidden=T|Text=LD02YD104KAB2A|Name=Part Number
|RECORD=41|OwnerIndex=2265|IndexInSheet=13|OwnerPartId=-1|Location.X=1151|Location.Y=322|Color=8388608|FontID=1|IsHidden=T|Text=AVX Interconnect / Elco|Name=Manufacturer
|RECORD=34|OwnerIndex=2265|IndexInSheet=-1|OwnerPartId=-1|Location.X=1160|Location.Y=280|Orientation=1|Color=8388608|FontID=2|Text=C67|Name=Designator|ReadOnlyState=1
|RECORD=41|OwnerIndex=2265|IndexInSheet=-1|OwnerPartId=-1|Location.X=1170|Location.Y=250|Orientation=1|Color=8388608|FontID=2|Text=0.1uF_0402|Name=Comment
|RECORD=44|OwnerIndex=2265
|RECORD=45|OwnerIndex=2286|IndexInSheet=-1|Description=Chip Capacitor, 2-Leads, Body 1.00x0.50mm, IPC Medium Density|UseComponentLibrary=T|ModelName=CAPC1005X56X25NL10T15|ModelType=PCBLIB|DatafileCount=1|ModelDatafileEntity0=CAPC1005X56X25NL10T15|ModelDatafileKind0=PCBLib|IsCurrent=T|DatalinksLocked=T|DatabaseDatalinksLocked=T
|RECORD=46|OwnerIndex=2287
|RECORD=48|OwnerIndex=2287
|RECORD=41|OwnerIndex=2289|IndexInSheet=-1|OwnerPartId=-1|Color=8388608|FontID=1|IsHidden=T|Text=2D|Name=Available Preview Images
|RECORD=45|OwnerIndex=2286|IndexInSheet=-1|Description=Chip Capacitor, 2-Leads, Body 1.00x0.50mm, IPC High Density|UseComponentLibrary=T|ModelName=CAPC1005X56X25LL10T15|ModelType=PCBLIB|DatafileCount=1|ModelDatafileEntity0=CAPC1005X56X25LL10T15|ModelDatafileKind0=PCBLib|DatalinksLocked=T|DatabaseDatalinksLocked=T
|RECORD=46|OwnerIndex=2291
|RECORD=48|OwnerIndex=2291
|RECORD=41|OwnerIndex=2293|IndexInSheet=-1|OwnerPartId=-1|Color=8388608|FontID=1|IsHidden=T|Text=2D|Name=Available Preview Images
|RECORD=45|OwnerIndex=2286|IndexInSheet=-1|Description=Chip Capacitor, 2-Leads, Body 1.00x0.50mm, IPC Low Density|UseComponentLibrary=T|ModelName=CAPC1005X56X25ML10T15|ModelType=PCBLIB|DatafileCount=1|ModelDatafileEntity0=CAPC1005X56X25ML10T15|ModelDatafileKind0=PCBLib|DatalinksLocked=T|DatabaseDatalinksLocked=T
|RECORD=46|OwnerIndex=2295
|RECORD=48|OwnerIndex=2295
|RECORD=41|OwnerIndex=2297|IndexInSheet=-1|OwnerPartId=-1|Color=8388608|FontID=1|IsHidden=T|Text=2D|Name=Available Preview Images
|RECORD=1|LibReference=b4654b650e69147ec39a6b967a45e02|ComponentDescription=None|PartCount=2|DisplayModeCount=1|IndexInSheet=210|OwnerPartId=-1|Location.X=1560|Location.Y=390|Orientation=1|CurrentPartId=1|LibraryPath=*|SourceLibraryName=Altium Content Vault|TargetFileName=*|AreaColor=11599871|Color=128|PartIDLocked=T|DesignItemId=CMP-14477-003537-2|AllPinCount=2
|RECORD=2|OwnerIndex=2299|OwnerPartId=1|Electrical=4|PinConglomerate=50|PinLength=7|Location.X=1567|Location.Y=390|Name=1|Designator=1|PinPropagationDelay=0.000000E+000
|RECORD=2|OwnerIndex=2299|OwnerPartId=1|Electrical=4|PinConglomerate=48|PinLength=6|Location.X=1574|Location.Y=390|Name=2|Designator=2|PinPropagationDelay=0.000000E+000
|RECORD=13|OwnerIndex=2299|IsNotAccesible=T|IndexInSheet=2|OwnerPartId=1|Location.X=1567|Location.Y=400|Corner.X=1567|Corner.Y=380|LineWidth=1|Color=16711680
|RECORD=13|OwnerIndex=2299|IsNotAccesible=T|IndexInSheet=3|OwnerPartId=1|Location.X=1573|Location.Y=400|Corner.X=1573|Corner.Y=380|LineWidth=1|Color=16711680
|RECORD=13|OwnerIndex=2299|IsNotAccesible=T|IndexInSheet=4|OwnerPartId=1|Location.X=1567|Location.Y=390|Corner.X=1564|Corner.Y=390|LineWidth=1|Color=16711680
|RECORD=13|OwnerIndex=2299|IsNotAccesible=T|IndexInSheet=5|OwnerPartId=1|Location.X=1574|Location.Y=390|Corner.X=1575|Corner.Y=390|LineWidth=1|Color=16711680
|RECORD=41|OwnerIndex=2299|IndexInSheet=6|OwnerPartId=-1|Location.X=1558|Location.Y=401|Color=8388608|FontID=1|IsHidden=T|Text=0.5mm|Name=Height
|RECORD=41|OwnerIndex=2299|IndexInSheet=7|OwnerPartId=-1|Location.X=1558|Location.Y=401|Color=8388608|FontID=1|IsHidden=T|Text=10000|Name=Package Quantity
|RECORD=41|OwnerIndex=2299|IndexInSheet=8|OwnerPartId=-1|Location.X=1558|Location.Y=401|Color=8388608|FontID=1|IsHidden=T|Text=M|Name=Series
|RECORD=41|OwnerIndex=2299|IndexInSheet=9|OwnerPartId=-1|Location.X=1558|Location.Y=401|Color=8388608|FontID=1|IsHidden=T|Text=85°C|Name=Max Operating Temperature
|RECORD=41|OwnerIndex=2299|IndexInSheet=10|OwnerPartId=-1|Location.X=1558|Location.Y=401|Color=8388608|FontID=1|IsHidden=T|Text=0.02inch|Name=Width
|RECORD=41|OwnerIndex=2299|IndexInSheet=11|OwnerPartId=-1|Location.X=1558|Location.Y=401|Color=8388608|FontID=1|IsHidden=T|Text=20%|Name=Tolerance
|RECORD=41|OwnerIndex=2299|IndexInSheet=12|OwnerPartId=-1|Location.X=1558|Location.Y=401|Color=8388608|FontID=1|IsHidden=T|Text=Surface Mount|Name=Mount
|RECORD=41|OwnerIndex=2299|IndexInSheet=13|OwnerPartId=-1|Location.X=1558|Location.Y=401|Color=8388608|FontID=1|IsHidden=T|Text=16V|Name=Voltage Rating (DC)
|RECORD=41|OwnerIndex=2299|IndexInSheet=14|OwnerPartId=-1|Location.X=1558|Location.Y=401|Color=8388608|FontID=1|IsHidden=T|Text=0.022inch|Name=Thickness
|RECORD=41|OwnerIndex=2299|IndexInSheet=15|OwnerPartId=-1|Location.X=1558|Location.Y=401|Color=8388608|FontID=1|IsHidden=T|Text=1mm|Name=Length
|RECORD=41|OwnerIndex=2299|IndexInSheet=16|OwnerPartId=-1|Location.X=1558|Location.Y=401|Color=8388608|FontID=1|IsHidden=T|Text=-55°C|Name=Min Operating Temperature
|RECORD=41|OwnerIndex=2299|IndexInSheet=17|OwnerPartId=-1|Location.X=1558|Location.Y=401|Color=8388608|FontID=1|IsHidden=T|Text=1uF|Name=Capacitance
|RECORD=41|OwnerIndex=2299|IndexInSheet=18|OwnerPartId=-1|Location.X=1558|Location.Y=401|Color=8388608|FontID=1|IsHidden=T|Text=X5R|Name=Dielectric
|RECORD=41|OwnerIndex=2299|IndexInSheet=19|OwnerPartId=-1|Location.X=1558|Location.Y=401|Color=8388608|FontID=1|IsHidden=T|Text=0.5mm|Name=Depth
|RECORD=41|OwnerIndex=2299|IndexInSheet=20|OwnerPartId=-1|Location.X=1558|Location.Y=401|Color=8388608|FontID=1|IsHidden=T|Text=Yes|Name=RoHS Compliant
|RECORD=41|OwnerIndex=2299|IndexInSheet=21|OwnerPartId=-1|Location.X=1558|Location.Y=401|Color=8388608|FontID=1|IsHidden=T|Text=Flat|Name=Construction
|RECORD=41|OwnerIndex=2299|IndexInSheet=22|OwnerPartId=-1|Location.X=1558|Location.Y=401|Color=8388608|FontID=1|IsHidden=T|Text=0402|Name=Case/Package
|RECORD=41|OwnerIndex=2299|IndexInSheet=23|OwnerPartId=-1|Location.X=1558|Location.Y=401|Color=8388608|FontID=1|IsHidden=T|Text=No|Name=Radiation Hardening
|RECORD=41|OwnerIndex=2299|IndexInSheet=24|OwnerPartId=-1|Location.X=1558|Location.Y=401|Color=8388608|FontID=1|IsHidden=T|Text=Tape and Reel|Name=Packaging
|RECORD=41|OwnerIndex=2299|IndexInSheet=25|OwnerPartId=-1|Location.X=1558|Location.Y=401|Color=8388608|FontID=1|IsHidden=T|Text=16V|Name=Voltage
|RECORD=41|OwnerIndex=2299|IndexInSheet=26|OwnerPartId=-1|Location.X=1558|Location.Y=401|Color=8388608|FontID=1|IsHidden=T|Text=16V|Name=Voltage Rating
|RECORD=41|OwnerIndex=2299|IndexInSheet=27|OwnerPartId=-1|Location.X=1558|Location.Y=401|Color=8388608|FontID=1|IsHidden=T|Text=Halogen Free|Name=Halogen Free
|RECORD=34|OwnerIndex=2299|IndexInSheet=-1|OwnerPartId=-1|Location.X=1563|Location.Y=401|Color=8388608|FontID=1|Text=C65|Name=Designator|ReadOnlyState=1
|RECORD=41|OwnerIndex=2299|IndexInSheet=-1|OwnerPartId=1|Location.X=1563|Location.Y=369|Color=8388608|FontID=1|Text=1uF_0402|Name=Comment
|RECORD=44|OwnerIndex=2299
|RECORD=45|OwnerIndex=2332|IndexInSheet=-1|UseComponentLibrary=T|ModelName=EMK105BJ105_V-F|ModelType=SIM|IsCurrent=T|DatalinksLocked=T|DatabaseDatalinksLocked=T
|RECORD=46|OwnerIndex=2333
|RECORD=48|OwnerIndex=2333
|RECORD=41|OwnerIndex=2335|IndexInSheet=-1|OwnerPartId=-1|Color=8388608|FontID=1|IsHidden=T|Text=General|Name=Kind
|RECORD=41|OwnerIndex=2335|IndexInSheet=-1|OwnerPartId=-1|Color=8388608|FontID=1|IsHidden=T|Text=Spice Subcircuit|Name=SubKind
|RECORD=41|OwnerIndex=2335|IndexInSheet=-1|OwnerPartId=-1|Color=8388608|FontID=1|IsHidden=T|Name=Spice Prefix
|RECORD=41|OwnerIndex=2335|IndexInSheet=-1|OwnerPartId=-1|Color=8388608|FontID=1|IsHidden=T|Name=Excluded Parts
|RECORD=41|OwnerIndex=2335|IndexInSheet=-1|OwnerPartId=-1|Color=8388608|FontID=1|IsHidden=T|Name=Netlist
|RECORD=41|OwnerIndex=2335|IndexInSheet=-1|OwnerPartId=-1|Color=8388608|FontID=1|IsHidden=T|Text=document_sim_cache\YSTRYKDD\0|Name=SimulationCacheLocation|ReadOnlyState=3
|RECORD=45|OwnerIndex=2332|IndexInSheet=-1|UseComponentLibrary=T|ModelName=FP-0402-L_1_0_0_05-W_0_5-IPC_C|ModelType=PCBLIB|DatafileCount=1|ModelDatafileEntity0=FP-0402-L_1_0_0_05-W_0_5-IPC_C|ModelDatafileKind0=PCBLib|IsCurrent=T|DatalinksLocked=T|DatabaseDatalinksLocked=T
|RECORD=46|OwnerIndex=2342
|RECORD=48|OwnerIndex=2342
|RECORD=45|OwnerIndex=2332|IndexInSheet=-1|UseComponentLibrary=T|ModelName=FP-0402-L_1_0_0_05-W_0_5-IPC_A|ModelType=PCBLIB|DatafileCount=1|ModelDatafileEntity0=FP-0402-L_1_0_0_05-W_0_5-IPC_A|ModelDatafileKind0=PCBLib|DatalinksLocked=T|DatabaseDatalinksLocked=T
|RECORD=46|OwnerIndex=2345
|RECORD=48|OwnerIndex=2345
|RECORD=45|OwnerIndex=2332|IndexInSheet=-1|UseComponentLibrary=T|ModelName=FP-0402-L_1_0_0_05-W_0_5-MFG|ModelType=PCBLIB|DatafileCount=1|ModelDatafileEntity0=FP-0402-L_1_0_0_05-W_0_5-MFG|ModelDatafileKind0=PCBLib|DatalinksLocked=T|DatabaseDatalinksLocked=T
|RECORD=46|OwnerIndex=2348
|RECORD=48|OwnerIndex=2348
|RECORD=45|OwnerIndex=2332|IndexInSheet=-1|UseComponentLibrary=T|ModelName=FP-0402-L_1_0_0_05-W_0_5-IPC_B|ModelType=PCBLIB|DatafileCount=1|ModelDatafileEntity0=FP-0402-L_1_0_0_05-W_0_5-IPC_B|ModelDatafileKind0=PCBLib|DatalinksLocked=T|DatabaseDatalinksLocked=T
|RECORD=46|OwnerIndex=2351
|RECORD=48|OwnerIndex=2351
|RECORD=27|IndexInSheet=211|OwnerPartId=-1|LineWidth=1|Color=8388608|LocationCount=2|X1=190|Y1=880|X2=190|Y2=850
|RECORD=27|IndexInSheet=212|OwnerPartId=-1|LineWidth=1|Color=8388608|LocationCount=2|X1=240|Y1=840|X2=240|Y2=850
|RECORD=27|IndexInSheet=213|OwnerPartId=-1|LineWidth=1|Color=8388608|LocationCount=2|X1=1640|Y1=810|X2=1560|Y2=810
|RECORD=27|IndexInSheet=214|OwnerPartId=-1|LineWidth=1|Color=8388608|LocationCount=2|X1=1560|Y1=800|X2=1640|Y2=800
|RECORD=27|IndexInSheet=215|OwnerPartId=-1|LineWidth=1|Color=8388608|LocationCount=3|X1=1560|Y1=770|X2=1600|Y2=770|X3=1600|Y3=710
|RECORD=27|IndexInSheet=216|OwnerPartId=-1|LineWidth=1|Color=8388608|LocationCount=3|X1=1450|Y1=810|X2=1410|Y2=810|X3=1410|Y3=860
|RECORD=27|IndexInSheet=217|OwnerPartId=-1|LineWidth=1|Color=8388608|LocationCount=2|X1=1410|Y1=810|X2=1410|Y2=750
|RECORD=27|IndexInSheet=218|OwnerPartId=-1|LineWidth=1|Color=8388608|LocationCount=2|X1=1360|Y1=860|X2=1360|Y2=840
|RECORD=27|IndexInSheet=219|OwnerPartId=-1|LineWidth=1|Color=8388608|LocationCount=3|X1=1450|Y1=770|X2=1360|Y2=770|X3=1360|Y3=800
|RECORD=27|IndexInSheet=220|OwnerPartId=-1|LineWidth=1|Color=8388608|LocationCount=2|X1=1410|Y1=720|X2=1410|Y2=710
|RECORD=27|IndexInSheet=221|OwnerPartId=-1|LineWidth=1|Color=8388608|LocationCount=2|X1=1360|Y1=770|X2=1340|Y2=770
|RECORD=27|IndexInSheet=222|OwnerPartId=-1|LineWidth=1|Color=8388608|LocationCount=2|X1=800|Y1=190|X2=800|Y2=170
|RECORD=27|IndexInSheet=223|OwnerPartId=-1|LineWidth=1|Color=8388608|LocationCount=2|X1=750|Y1=190|X2=750|Y2=170
|RECORD=27|IndexInSheet=224|OwnerPartId=-1|LineWidth=1|Color=8388608|LocationCount=3|X1=830|Y1=310|X2=800|Y2=310|X3=800|Y3=220
|RECORD=27|IndexInSheet=225|OwnerPartId=-1|LineWidth=1|Color=8388608|LocationCount=3|X1=830|Y1=320|X2=750|Y2=320|X3=750|Y3=220
|RECORD=27|IndexInSheet=226|OwnerPartId=-1|LineWidth=1|Color=8388608|LocationCount=2|X1=800|Y1=310|X2=800|Y2=370
|RECORD=27|IndexInSheet=227|OwnerPartId=-1|LineWidth=1|Color=8388608|LocationCount=2|X1=750|Y1=320|X2=750|Y2=370
|RECORD=27|IndexInSheet=228|OwnerPartId=-1|LineWidth=1|Color=8388608|LocationCount=2|X1=970|Y1=310|X2=1050|Y2=310
|RECORD=27|IndexInSheet=229|OwnerPartId=-1|LineWidth=1|Color=8388608|LocationCount=2|X1=970|Y1=320|X2=1050|Y2=320
|RECORD=27|IndexInSheet=230|OwnerPartId=-1|LineWidth=1|Color=8388608|LocationCount=3|X1=970|Y1=290|X2=1010|Y2=290|X3=1010|Y3=370
|RECORD=27|IndexInSheet=231|OwnerPartId=-1|LineWidth=1|Color=8388608|LocationCount=3|X1=970|Y1=300|X2=1050|Y2=300|X3=1050|Y3=170
|RECORD=27|IndexInSheet=232|OwnerPartId=-1|LineWidth=1|Color=8388608|LocationCount=2|X1=970|Y1=260|X2=1010|Y2=260
|RECORD=27|IndexInSheet=233|OwnerPartId=-1|LineWidth=1|Color=8388608|LocationCount=2|X1=1530|Y1=1030|X2=1530|Y2=1000
|RECORD=27|IndexInSheet=234|OwnerPartId=-1|LineWidth=1|Color=8388608|LocationCount=2|X1=1580|Y1=1030|X2=1580|Y2=1000
|RECORD=27|IndexInSheet=235|OwnerPartId=-1|LineWidth=1|Color=8388608|LocationCount=2|X1=1580|Y1=960|X2=1580|Y2=920
|RECORD=27|IndexInSheet=236|OwnerPartId=-1|LineWidth=1|Color=8388608|LocationCount=2|X1=1530|Y1=960|X2=1530|Y2=920
|RECORD=27|IndexInSheet=237|OwnerPartId=-1|LineWidth=1|Color=8388608|LocationCount=2|X1=80|Y1=670|X2=80|Y2=640
|RECORD=27|IndexInSheet=238|OwnerPartId=-1|LineWidth=1|Color=8388608|LocationCount=2|X1=130|Y1=630|X2=130|Y2=640
|RECORD=27|IndexInSheet=239|OwnerPartId=-1|LineWidth=1|Color=8388608|LocationCount=2|X1=180|Y1=650|X2=180|Y2=630
|RECORD=27|IndexInSheet=240|OwnerPartId=-1|LineWidth=1|Color=8388608|LocationCount=2|X1=230|Y1=630|X2=230|Y2=650
|RECORD=27|IndexInSheet=241|OwnerPartId=-1|LineWidth=1|Color=8388608|LocationCount=4|X1=130|Y1=600|X2=130|Y2=590|X3=80|Y3=590|X4=80|Y4=610
|RECORD=27|IndexInSheet=242|OwnerPartId=-1|LineWidth=1|Color=8388608|LocationCount=4|X1=230|Y1=600|X2=230|Y2=590|X3=180|Y3=590|X4=180|Y4=610
|RECORD=27|IndexInSheet=243|OwnerPartId=-1|LineWidth=1|Color=8388608|LocationCount=4|X1=240|Y1=810|X2=240|Y2=800|X3=190|Y3=800|X4=190|Y4=820
|RECORD=27|IndexInSheet=244|OwnerPartId=-1|LineWidth=1|Color=8388608|LocationCount=4|X1=340|Y1=810|X2=340|Y2=800|X3=290|Y3=800|X4=290|Y4=820
|RECORD=27|IndexInSheet=245|OwnerPartId=-1|LineWidth=1|Color=8388608|LocationCount=3|X1=180|Y1=110|X2=140|Y2=110|X3=140|Y3=70
|RECORD=27|IndexInSheet=246|OwnerPartId=-1|LineWidth=1|Color=8388608|LocationCount=3|X1=260|Y1=110|X2=300|Y2=110|X3=300|Y3=70
|RECORD=27|IndexInSheet=247|OwnerPartId=-1|LineWidth=1|Color=8388608|LocationCount=3|X1=180|Y1=100|X2=160|Y2=100|X3=160|Y3=190
|RECORD=27|IndexInSheet=248|OwnerPartId=-1|LineWidth=1|Color=8388608|LocationCount=3|X1=260|Y1=100|X2=280|Y2=100|X3=280|Y3=190
|RECORD=27|IndexInSheet=249|OwnerPartId=-1|LineWidth=1|Color=8388608|LocationCount=2|X1=260|Y1=150|X2=330|Y2=150
|RECORD=27|IndexInSheet=250|OwnerPartId=-1|LineWidth=1|Color=8388608|LocationCount=2|X1=260|Y1=140|X2=330|Y2=140
|RECORD=27|IndexInSheet=251|OwnerPartId=-1|LineWidth=1|Color=8388608|LocationCount=2|X1=260|Y1=130|X2=330|Y2=130
|RECORD=27|IndexInSheet=252|OwnerPartId=-1|LineWidth=1|Color=8388608|LocationCount=2|X1=260|Y1=120|X2=330|Y2=120
|RECORD=27|IndexInSheet=253|OwnerPartId=-1|LineWidth=1|Color=8388608|LocationCount=2|X1=110|Y1=150|X2=180|Y2=150
|RECORD=27|IndexInSheet=254|OwnerPartId=-1|LineWidth=1|Color=8388608|LocationCount=2|X1=110|Y1=140|X2=180|Y2=140
|RECORD=27|IndexInSheet=255|OwnerPartId=-1|LineWidth=1|Color=8388608|LocationCount=2|X1=110|Y1=130|X2=180|Y2=130
|RECORD=27|IndexInSheet=256|OwnerPartId=-1|LineWidth=1|Color=8388608|LocationCount=2|X1=110|Y1=120|X2=180|Y2=120
|RECORD=27|IndexInSheet=257|OwnerPartId=-1|LineWidth=1|Color=8388608|LocationCount=3|X1=690|Y1=860|X2=710|Y2=860|X3=710|Y3=790
|RECORD=27|IndexInSheet=258|OwnerPartId=-1|LineWidth=1|Color=8388608|LocationCount=3|X1=340|Y1=860|X2=290|Y2=860|X3=290|Y3=840
|RECORD=27|IndexInSheet=259|OwnerPartId=-1|LineWidth=1|Color=8388608|LocationCount=2|X1=290|Y1=860|X2=290|Y2=880
|RECORD=27|IndexInSheet=260|OwnerPartId=-1|LineWidth=1|Color=8388608|LocationCount=3|X1=550|Y1=1030|X2=470|Y2=1030|X3=470|Y3=860
|RECORD=27|IndexInSheet=261|OwnerPartId=-1|LineWidth=1|Color=8388608|LocationCount=3|X1=550|Y1=1020|X2=480|Y2=1020|X3=480|Y3=850
|RECORD=27|IndexInSheet=262|OwnerPartId=-1|LineWidth=1|Color=8388608|LocationCount=3|X1=550|Y1=1010|X2=490|Y2=1010|X3=490|Y3=840
|RECORD=27|IndexInSheet=263|OwnerPartId=-1|LineWidth=1|Color=8388608|LocationCount=3|X1=550|Y1=1000|X2=500|Y2=1000|X3=500|Y3=830
|RECORD=27|IndexInSheet=264|OwnerPartId=-1|LineWidth=1|Color=8388608|LocationCount=3|X1=660|Y1=1030|X2=770|Y2=1030|X3=770|Y3=830
|RECORD=27|IndexInSheet=265|OwnerPartId=-1|LineWidth=1|Color=8388608|LocationCount=3|X1=660|Y1=1020|X2=760|Y2=1020|X3=760|Y3=840
|RECORD=27|IndexInSheet=266|OwnerPartId=-1|LineWidth=1|Color=8388608|LocationCount=3|X1=660|Y1=1010|X2=750|Y2=1010|X3=750|Y3=850
|RECORD=27|IndexInSheet=267|OwnerPartId=-1|LineWidth=1|Color=8388608|LocationCount=3|X1=660|Y1=1000|X2=710|Y2=1000|X3=710|Y3=860
|RECORD=27|IndexInSheet=268|OwnerPartId=-1|LineWidth=1|Color=8388608|LocationCount=3|X1=440|Y1=520|X2=410|Y2=520|X3=410|Y3=650
|RECORD=27|IndexInSheet=269|OwnerPartId=-1|LineWidth=1|Color=8388608|LocationCount=3|X1=440|Y1=510|X2=400|Y2=510|X3=400|Y3=640
|RECORD=27|IndexInSheet=270|OwnerPartId=-1|LineWidth=1|Color=8388608|LocationCount=3|X1=440|Y1=500|X2=390|Y2=500|X3=390|Y3=630
|RECORD=27|IndexInSheet=271|OwnerPartId=-1|LineWidth=1|Color=8388608|LocationCount=3|X1=440|Y1=490|X2=380|Y2=490|X3=380|Y3=620
|RECORD=27|IndexInSheet=272|OwnerPartId=-1|LineWidth=1|Color=8388608|LocationCount=3|X1=550|Y1=490|X2=590|Y2=490|X3=590|Y3=650
|RECORD=27|IndexInSheet=273|OwnerPartId=-1|LineWidth=1|Color=8388608|LocationCount=3|X1=550|Y1=520|X2=660|Y2=520|X3=660|Y3=620
|RECORD=27|IndexInSheet=274|OwnerPartId=-1|LineWidth=1|Color=8388608|LocationCount=3|X1=550|Y1=510|X2=650|Y2=510|X3=650|Y3=630
|RECORD=27|IndexInSheet=275|OwnerPartId=-1|LineWidth=1|Color=8388608|LocationCount=3|X1=550|Y1=500|X2=640|Y2=500|X3=640|Y3=640
|RECORD=27|IndexInSheet=276|OwnerPartId=-1|LineWidth=1|Color=8388608|LocationCount=3|X1=500|Y1=150|X2=580|Y2=150|X3=580|Y3=180
|RECORD=27|IndexInSheet=277|OwnerPartId=-1|LineWidth=1|Color=8388608|LocationCount=3|X1=500|Y1=140|X2=550|Y2=140|X3=550|Y3=70
|RECORD=27|IndexInSheet=278|OwnerPartId=-1|LineWidth=1|Color=8388608|LocationCount=2|X1=500|Y1=130|X2=570|Y2=130
|RECORD=27|IndexInSheet=279|OwnerPartId=-1|LineWidth=1|Color=8388608|LocationCount=2|X1=500|Y1=120|X2=570|Y2=120
|RECORD=27|IndexInSheet=280|OwnerPartId=-1|LineWidth=1|Color=8388608|LocationCount=2|X1=640|Y1=100|X2=690|Y2=100
|RECORD=27|IndexInSheet=281|OwnerPartId=-1|LineWidth=1|Color=8388608|LocationCount=4|X1=500|Y1=110|X2=570|Y2=110|X3=570|Y3=100|X4=600|Y4=100
|RECORD=27|IndexInSheet=282|OwnerPartId=-1|LineWidth=1|Color=8388608|LocationCount=3|X1=420|Y1=620|X2=380|Y2=620|X3=330|Y3=620
|RECORD=27|IndexInSheet=283|OwnerPartId=-1|LineWidth=1|Color=8388608|LocationCount=3|X1=420|Y1=630|X2=390|Y2=630|X3=330|Y3=630
|RECORD=27|IndexInSheet=284|OwnerPartId=-1|LineWidth=1|Color=8388608|LocationCount=5|X1=80|Y1=630|X2=80|Y2=640|X3=130|Y3=640|X4=400|Y4=640|X5=420|Y5=640
|RECORD=27|IndexInSheet=285|OwnerPartId=-1|LineWidth=1|Color=8388608|LocationCount=5|X1=180|Y1=670|X2=180|Y2=650|X3=230|Y3=650|X4=410|Y4=650|X5=420|Y5=650
|RECORD=27|IndexInSheet=286|OwnerPartId=-1|LineWidth=1|Color=8388608|LocationCount=3|X1=580|Y1=620|X2=660|Y2=620|X3=670|Y3=620
|RECORD=27|IndexInSheet=287|OwnerPartId=-1|LineWidth=1|Color=8388608|LocationCount=3|X1=670|Y1=630|X2=650|Y2=630|X3=580|Y3=630
|RECORD=27|IndexInSheet=288|OwnerPartId=-1|LineWidth=1|Color=8388608|LocationCount=3|X1=670|Y1=640|X2=640|Y2=640|X3=580|Y3=640
|RECORD=27|IndexInSheet=289|OwnerPartId=-1|LineWidth=1|Color=8388608|LocationCount=4|X1=580|Y1=650|X2=590|Y2=650|X3=600|Y3=650|X4=600|Y4=580
|RECORD=27|IndexInSheet=290|OwnerPartId=-1|LineWidth=1|Color=8388608|LocationCount=3|X1=530|Y1=830|X2=500|Y2=830|X3=440|Y3=830
|RECORD=27|IndexInSheet=291|OwnerPartId=-1|LineWidth=1|Color=8388608|LocationCount=4|X1=530|Y1=860|X2=470|Y2=860|X3=340|Y3=860|X4=340|Y4=840
|RECORD=27|IndexInSheet=292|OwnerPartId=-1|LineWidth=1|Color=8388608|LocationCount=5|X1=190|Y1=840|X2=190|Y2=850|X3=240|Y3=850|X4=480|Y4=850|X5=530|Y5=850
|RECORD=27|IndexInSheet=293|OwnerPartId=-1|LineWidth=1|Color=8388608|LocationCount=3|X1=530|Y1=840|X2=490|Y2=840|X3=440|Y3=840
|RECORD=27|IndexInSheet=294|OwnerPartId=-1|LineWidth=1|Color=8388608|LocationCount=3|X1=780|Y1=830|X2=770|Y2=830|X3=690|Y3=830
|RECORD=27|IndexInSheet=295|OwnerPartId=-1|LineWidth=1|Color=8388608|LocationCount=3|X1=780|Y1=840|X2=760|Y2=840|X3=690|Y3=840
|RECORD=27|IndexInSheet=296|OwnerPartId=-1|LineWidth=1|Color=8388608|LocationCount=3|X1=780|Y1=850|X2=750|Y2=850|X3=690|Y3=850
|RECORD=27|IndexInSheet=297|OwnerPartId=-1|LineWidth=1|Color=8388608|LocationCount=2|X1=100|Y1=490|X2=100|Y2=460
|RECORD=27|IndexInSheet=298|OwnerPartId=-1|LineWidth=1|Color=8388608|LocationCount=2|X1=150|Y1=450|X2=150|Y2=460
|RECORD=27|IndexInSheet=299|OwnerPartId=-1|LineWidth=1|Color=8388608|LocationCount=2|X1=200|Y1=470|X2=200|Y2=450
|RECORD=27|IndexInSheet=300|OwnerPartId=-1|LineWidth=1|Color=8388608|LocationCount=2|X1=250|Y1=450|X2=250|Y2=470
|RECORD=27|IndexInSheet=301|OwnerPartId=-1|LineWidth=1|Color=8388608|LocationCount=4|X1=150|Y1=420|X2=150|Y2=410|X3=100|Y3=410|X4=100|Y4=430
|RECORD=27|IndexInSheet=302|OwnerPartId=-1|LineWidth=1|Color=8388608|LocationCount=4|X1=250|Y1=420|X2=250|Y2=410|X3=200|Y3=410|X4=200|Y4=430
|RECORD=27|IndexInSheet=303|OwnerPartId=-1|LineWidth=1|Color=8388608|LocationCount=4|X1=100|Y1=450|X2=100|Y2=460|X3=150|Y3=460|X4=440|Y4=460
|RECORD=27|IndexInSheet=304|OwnerPartId=-1|LineWidth=1|Color=8388608|LocationCount=4|X1=200|Y1=490|X2=200|Y2=470|X3=250|Y3=470|X4=440|Y4=470
|RECORD=27|IndexInSheet=305|OwnerPartId=-1|LineWidth=1|Color=8388608|LocationCount=3|X1=550|Y1=440|X2=590|Y2=440|X3=590|Y3=410
|RECORD=27|IndexInSheet=306|OwnerPartId=-1|LineWidth=1|Color=8388608|LocationCount=3|X1=660|Y1=950|X2=680|Y2=950|X3=680|Y3=930
|RECORD=27|IndexInSheet=307|OwnerPartId=-1|LineWidth=1|Color=8388608|LocationCount=2|X1=120|Y1=1000|X2=120|Y2=970
|RECORD=27|IndexInSheet=308|OwnerPartId=-1|LineWidth=1|Color=8388608|LocationCount=2|X1=170|Y1=960|X2=170|Y2=970
|RECORD=27|IndexInSheet=309|OwnerPartId=-1|LineWidth=1|Color=8388608|LocationCount=4|X1=170|Y1=930|X2=170|Y2=920|X3=120|Y3=920|X4=120|Y4=940
|RECORD=27|IndexInSheet=310|OwnerPartId=-1|LineWidth=1|Color=8388608|LocationCount=4|X1=270|Y1=930|X2=270|Y2=920|X3=220|Y3=920|X4=220|Y4=940
|RECORD=27|IndexInSheet=311|OwnerPartId=-1|LineWidth=1|Color=8388608|LocationCount=3|X1=270|Y1=980|X2=220|Y2=980|X3=220|Y3=960
|RECORD=27|IndexInSheet=312|OwnerPartId=-1|LineWidth=1|Color=8388608|LocationCount=2|X1=220|Y1=980|X2=220|Y2=1000
|RECORD=27|IndexInSheet=313|OwnerPartId=-1|LineWidth=1|Color=8388608|LocationCount=3|X1=550|Y1=980|X2=270|Y2=980|X3=270|Y3=960
|RECORD=27|IndexInSheet=314|OwnerPartId=-1|LineWidth=1|Color=8388608|LocationCount=4|X1=120|Y1=960|X2=120|Y2=970|X3=170|Y3=970|X4=550|Y4=970
|RECORD=27|IndexInSheet=315|OwnerPartId=-1|LineWidth=1|Color=8388608|LocationCount=2|X1=410|Y1=960|X2=550|Y2=960
|RECORD=27|IndexInSheet=316|OwnerPartId=-1|LineWidth=1|Color=8388608|LocationCount=2|X1=550|Y1=950|X2=410|Y2=950
|RECORD=27|IndexInSheet=317|OwnerPartId=-1|LineWidth=1|Color=8388608|LocationCount=2|X1=660|Y1=980|X2=810|Y2=980
|RECORD=27|IndexInSheet=318|OwnerPartId=-1|LineWidth=1|Color=8388608|LocationCount=2|X1=810|Y1=970|X2=660|Y2=970
|RECORD=27|IndexInSheet=319|OwnerPartId=-1|LineWidth=1|Color=8388608|LocationCount=2|X1=660|Y1=960|X2=810|Y2=960
|RECORD=27|IndexInSheet=320|OwnerPartId=-1|LineWidth=1|Color=8388608|LocationCount=2|X1=370|Y1=450|X2=440|Y2=450
|RECORD=27|IndexInSheet=321|OwnerPartId=-1|LineWidth=1|Color=8388608|LocationCount=2|X1=440|Y1=440|X2=370|Y2=440
|RECORD=27|IndexInSheet=322|OwnerPartId=-1|LineWidth=1|Color=8388608|LocationCount=2|X1=550|Y1=470|X2=640|Y2=470
|RECORD=27|IndexInSheet=323|OwnerPartId=-1|LineWidth=1|Color=8388608|LocationCount=2|X1=640|Y1=460|X2=550|Y2=460
|RECORD=27|IndexInSheet=324|OwnerPartId=-1|LineWidth=1|Color=8388608|LocationCount=2|X1=550|Y1=450|X2=640|Y2=450
|RECORD=27|IndexInSheet=325|OwnerPartId=-1|LineWidth=1|Color=8388608|LocationCount=4|X1=970|Y1=270|X2=1010|Y2=270|X3=1010|Y3=260|X4=1010|Y4=170
|RECORD=27|IndexInSheet=326|OwnerPartId=-1|LineWidth=1|Color=8388608|LocationCount=4|X1=1490|Y1=200|X2=1510|Y2=200|X3=1510|Y3=190|X4=1510|Y4=170
|RECORD=27|IndexInSheet=327|OwnerPartId=-1|LineWidth=1|Color=8388608|LocationCount=2|X1=1490|Y1=190|X2=1510|Y2=190
|RECORD=27|IndexInSheet=328|OwnerPartId=-1|LineWidth=1|Color=8388608|LocationCount=3|X1=1120|Y1=320|X2=1120|Y2=400|X3=1120|Y3=440
|RECORD=27|IndexInSheet=329|OwnerPartId=-1|LineWidth=1|Color=8388608|LocationCount=4|X1=1160|Y1=320|X2=1160|Y2=360|X3=1160|Y3=390|X4=1160|Y4=440
|RECORD=27|IndexInSheet=330|OwnerPartId=-1|LineWidth=1|Color=8388608|LocationCount=3|X1=1160|Y1=290|X2=1160|Y2=270|X3=1160|Y3=240
|RECORD=27|IndexInSheet=331|OwnerPartId=-1|LineWidth=1|Color=8388608|LocationCount=2|X1=1120|Y1=240|X2=1120|Y2=290
|RECORD=27|IndexInSheet=332|OwnerPartId=-1|LineWidth=1|Color=8388608|LocationCount=2|X1=1300|Y1=390|X2=1160|Y2=390
|RECORD=27|IndexInSheet=333|OwnerPartId=-1|LineWidth=1|Color=8388608|LocationCount=2|X1=1300|Y1=400|X2=1120|Y2=400
|RECORD=27|IndexInSheet=334|OwnerPartId=-1|LineWidth=1|Color=8388608|LocationCount=3|X1=1490|Y1=290|X2=1640|Y2=290|X3=1640|Y3=360
|RECORD=27|IndexInSheet=335|OwnerPartId=-1|LineWidth=1|Color=8388608|LocationCount=2|X1=1640|Y1=210|X2=1640|Y2=230
|RECORD=27|IndexInSheet=336|OwnerPartId=-1|LineWidth=1|Color=8388608|LocationCount=2|X1=1640|Y1=270|X2=1640|Y2=290
|RECORD=27|IndexInSheet=337|OwnerPartId=-1|LineWidth=1|Color=8388608|LocationCount=3|X1=1490|Y1=300|X2=1600|Y2=300|X3=1600|Y3=210
|RECORD=27|IndexInSheet=338|OwnerPartId=-1|LineWidth=1|Color=8388608|LocationCount=2|X1=1490|Y1=320|X2=1560|Y2=320
|RECORD=27|IndexInSheet=339|OwnerPartId=-1|LineWidth=1|Color=8388608|LocationCount=2|X1=1560|Y1=310|X2=1490|Y2=310
|RECORD=27|IndexInSheet=340|OwnerPartId=-1|LineWidth=1|Color=8388608|LocationCount=3|X1=1300|Y1=280|X2=1210|Y2=280|X3=1210|Y3=230
|RECORD=27|IndexInSheet=341|OwnerPartId=-1|LineWidth=1|Color=8388608|LocationCount=3|X1=1300|Y1=270|X2=1240|Y2=270|X3=1240|Y3=230
|RECORD=27|IndexInSheet=342|OwnerPartId=-1|LineWidth=1|Color=8388608|LocationCount=2|X1=1490|Y1=270|X2=1510|Y2=270
|RECORD=27|IndexInSheet=343|OwnerPartId=-1|LineWidth=1|Color=8388608|LocationCount=2|X1=1160|Y1=360|X2=1210|Y2=360
|RECORD=27|IndexInSheet=344|OwnerPartId=-1|LineWidth=1|Color=8388608|LocationCount=4|X1=1250|Y1=360|X2=1290|Y2=360|X3=1290|Y3=350|X4=1300|Y4=350
|RECORD=27|IndexInSheet=345|OwnerPartId=-1|LineWidth=1|Color=8388608|LocationCount=2|X1=1110|Y1=340|X2=1210|Y2=340
|RECORD=27|IndexInSheet=346|OwnerPartId=-1|LineWidth=1|Color=8388608|LocationCount=3|X1=1250|Y1=340|X2=1290|Y2=340|X3=1290|Y3=350
|RECORD=27|IndexInSheet=347|OwnerPartId=-1|LineWidth=1|Color=8388608|LocationCount=2|X1=1210|Y1=140|X2=1210|Y2=190
|RECORD=27|IndexInSheet=348|OwnerPartId=-1|LineWidth=1|Color=8388608|LocationCount=5|X1=1170|Y1=170|X2=1170|Y2=140|X3=1210|Y3=140|X4=1240|Y4=140|X5=1240|Y5=190
|RECORD=27|IndexInSheet=349|OwnerPartId=-1|LineWidth=1|Color=8388608|LocationCount=5|X1=1300|Y1=310|X2=1200|Y2=310|X3=1200|Y3=300|X4=1200|Y4=270|X5=1160|Y5=270
|RECORD=27|IndexInSheet=350|OwnerPartId=-1|LineWidth=1|Color=8388608|LocationCount=2|X1=1300|Y1=300|X2=1200|Y2=300
|RECORD=27|IndexInSheet=351|OwnerPartId=-1|LineWidth=1|Color=8388608|LocationCount=2|X1=1560|Y1=430|X2=1640|Y2=430
|RECORD=27|IndexInSheet=352|OwnerPartId=-1|LineWidth=1|Color=8388608|LocationCount=4|X1=1640|Y1=400|X2=1640|Y2=430|X3=1640|Y3=460|X4=1640|Y4=470
|RECORD=27|IndexInSheet=353|OwnerPartId=-1|LineWidth=1|Color=8388608|LocationCount=4|X1=1520|Y1=430|X2=1510|Y2=430|X3=1510|Y3=400|X4=1490|Y4=400
|RECORD=27|IndexInSheet=354|OwnerPartId=-1|LineWidth=1|Color=8388608|LocationCount=2|X1=1490|Y1=360|X2=1510|Y2=360
|RECORD=27|IndexInSheet=355|OwnerPartId=-1|LineWidth=1|Color=8388608|LocationCount=2|X1=1600|Y1=460|X2=1640|Y2=460
|RECORD=27|IndexInSheet=356|OwnerPartId=-1|LineWidth=1|Color=8388608|LocationCount=2|X1=1560|Y1=460|X2=1530|Y2=460
|RECORD=27|IndexInSheet=357|OwnerPartId=-1|LineWidth=1|Color=8388608|LocationCount=4|X1=1490|Y1=380|X2=1520|Y2=380|X3=1520|Y3=390|X4=1560|Y4=390
|RECORD=27|IndexInSheet=358|OwnerPartId=-1|LineWidth=1|Color=8388608|LocationCount=3|X1=1580|Y1=390|X2=1600|Y2=390|X3=1600|Y3=300
|RECORD=27|IndexInSheet=359|OwnerPartId=-1|LineWidth=1|Color=8388608|LocationCount=2|X1=1550|Y1=270|X2=1570|Y2=270
|RECORD=27|IndexInSheet=360|OwnerPartId=-1|LineWidth=1|Color=8388608|LocationCount=2|X1=1260|Y1=330|X2=1300|Y2=330
|RECORD=27|IndexInSheet=361|OwnerPartId=-1|LineWidth=1|Color=8388608|LocationCount=2|X1=1490|Y1=340|X2=1510|Y2=340
|RECORD=27|IndexInSheet=362|OwnerPartId=-1|LineWidth=1|Color=8388608|LocationCount=2|X1=1330|Y1=590|X2=1370|Y2=590
|RECORD=27|IndexInSheet=363|OwnerPartId=-1|LineWidth=1|Color=8388608|LocationCount=2|X1=1330|Y1=540|X2=1370|Y2=540
|RECORD=27|IndexInSheet=364|OwnerPartId=-1|LineWidth=1|Color=8388608|LocationCount=2|X1=1400|Y1=590|X2=1460|Y2=590
|RECORD=27|IndexInSheet=365|OwnerPartId=-1|LineWidth=1|Color=8388608|LocationCount=2|X1=1400|Y1=540|X2=1460|Y2=540
|RECORD=1|LibReference=CAP|PartCount=2|DisplayModeCount=2|IndexInSheet=366|OwnerPartId=-1|Location.X=1390|Location.Y=580|Orientation=2|CurrentPartId=1|SourceLibraryName=Altium Content Vault|TargetFileName=*|AreaColor=11599871|Color=128|PartIDLocked=F|DesignItemId=CMP-2008-00031-1|AllPinCount=2
|RECORD=2|OwnerIndex=2509|OwnerPartId=1|OwnerPartDisplayMode=1|FormalType=1|Electrical=4|PinConglomerate=32|PinLength=10|Location.X=1390|Location.Y=590|Name=1|Designator=1|PinPropagationDelay=0.000000E+000
|RECORD=2|OwnerIndex=2509|OwnerPartId=1|OwnerPartDisplayMode=1|FormalType=1|Electrical=4|PinConglomerate=34|PinLength=10|Location.X=1380|Location.Y=590|Name=2|Designator=2|PinPropagationDelay=0.000000E+000
|RECORD=13|OwnerIndex=2509|IsNotAccesible=T|IndexInSheet=2|OwnerPartId=1|OwnerPartDisplayMode=1|Location.X=1390|Location.Y=598|Corner.X=1390|Corner.Y=582|LineWidth=1|Color=16711680
|RECORD=13|OwnerIndex=2509|IsNotAccesible=T|IndexInSheet=3|OwnerPartId=1|OwnerPartDisplayMode=1|Location.X=1386|Location.Y=590|Corner.X=1380|Corner.Y=590|LineWidth=1|Color=16711680
|RECORD=12|OwnerIndex=2509|IsNotAccesible=T|IndexInSheet=4|OwnerPartId=1|OwnerPartDisplayMode=1|Location.X=1370|Location.Y=590|Radius=16|LineWidth=1|StartAngle=331.000|EndAngle=360.000|Color=16711680
|RECORD=12|OwnerIndex=2509|IsNotAccesible=T|IndexInSheet=5|OwnerPartId=1|OwnerPartDisplayMode=1|Location.X=1370|Location.Y=590|Radius=16|LineWidth=1|StartAngle=360.000|EndAngle=29.000|Color=16711680
|RECORD=2|OwnerIndex=2509|OwnerPartId=1|FormalType=1|Electrical=4|PinConglomerate=32|PinLength=10|Location.X=1390|Location.Y=590|Name=1|Designator=1|PinPropagationDelay=0.000000E+000
|RECORD=2|OwnerIndex=2509|OwnerPartId=1|FormalType=1|Electrical=4|PinConglomerate=34|PinLength=10|Location.X=1380|Location.Y=590|Name=2|Designator=2|PinPropagationDelay=0.000000E+000
|RECORD=13|OwnerIndex=2509|IsNotAccesible=T|IndexInSheet=8|OwnerPartId=1|Location.X=1383|Location.Y=582|Corner.X=1383|Corner.Y=598|LineWidth=1|Color=16711680
|RECORD=13|OwnerIndex=2509|IsNotAccesible=T|IndexInSheet=9|OwnerPartId=1|Location.X=1387|Location.Y=598|Corner.X=1387|Corner.Y=582|LineWidth=1|Color=16711680
|RECORD=6|OwnerIndex=2509|IsNotAccesible=T|IndexInSheet=10|OwnerPartId=1|LineWidth=1|Color=16711680|LocationCount=2|X1=1390|Y1=590|X2=1387|Y2=590
|RECORD=6|OwnerIndex=2509|IsNotAccesible=T|IndexInSheet=11|OwnerPartId=1|LineWidth=1|Color=16711680|LocationCount=2|X1=1380|Y1=590|X2=1383|Y2=590
|RECORD=41|OwnerIndex=2509|IndexInSheet=12|OwnerPartId=-1|Location.X=1368|Location.Y=599|Color=8388608|FontID=1|IsHidden=T|Text=LD02YD104KAB2A|Name=Part Number
|RECORD=41|OwnerIndex=2509|IndexInSheet=13|OwnerPartId=-1|Location.X=1368|Location.Y=599|Color=8388608|FontID=1|IsHidden=T|Text=AVX Interconnect / Elco|Name=Manufacturer
|RECORD=34|OwnerIndex=2509|IndexInSheet=-1|OwnerPartId=-1|Location.X=1379|Location.Y=599|Color=8388608|FontID=1|Text=C32|Name=Designator|ReadOnlyState=1
|RECORD=41|OwnerIndex=2509|IndexInSheet=-1|OwnerPartId=-1|Location.X=1379|Location.Y=571|Color=8388608|FontID=1|Text=0.1uF_0402|Name=Comment
|RECORD=44|OwnerIndex=2509
|RECORD=45|OwnerIndex=2530|IndexInSheet=-1|Description=Chip Capacitor, 2-Leads, Body 1.00x0.50mm, IPC Medium Density|UseComponentLibrary=T|ModelName=CAPC1005X56X25NL10T15|ModelType=PCBLIB|DatafileCount=1|ModelDatafileEntity0=CAPC1005X56X25NL10T15|ModelDatafileKind0=PCBLib|IsCurrent=T|DatalinksLocked=T|DatabaseDatalinksLocked=T
|RECORD=46|OwnerIndex=2531
|RECORD=48|OwnerIndex=2531
|RECORD=41|OwnerIndex=2533|IndexInSheet=-1|OwnerPartId=-1|Color=8388608|FontID=1|IsHidden=T|Text=2D|Name=Available Preview Images
|RECORD=45|OwnerIndex=2530|IndexInSheet=-1|Description=Chip Capacitor, 2-Leads, Body 1.00x0.50mm, IPC High Density|UseComponentLibrary=T|ModelName=CAPC1005X56X25LL10T15|ModelType=PCBLIB|DatafileCount=1|ModelDatafileEntity0=CAPC1005X56X25LL10T15|ModelDatafileKind0=PCBLib|DatalinksLocked=T|DatabaseDatalinksLocked=T
|RECORD=46|OwnerIndex=2535
|RECORD=48|OwnerIndex=2535
|RECORD=41|OwnerIndex=2537|IndexInSheet=-1|OwnerPartId=-1|Color=8388608|FontID=1|IsHidden=T|Text=2D|Name=Available Preview Images
|RECORD=45|OwnerIndex=2530|IndexInSheet=-1|Description=Chip Capacitor, 2-Leads, Body 1.00x0.50mm, IPC Low Density|UseComponentLibrary=T|ModelName=CAPC1005X56X25ML10T15|ModelType=PCBLIB|DatafileCount=1|ModelDatafileEntity0=CAPC1005X56X25ML10T15|ModelDatafileKind0=PCBLib|DatalinksLocked=T|DatabaseDatalinksLocked=T
|RECORD=46|OwnerIndex=2539
|RECORD=48|OwnerIndex=2539
|RECORD=41|OwnerIndex=2541|IndexInSheet=-1|OwnerPartId=-1|Color=8388608|FontID=1|IsHidden=T|Text=2D|Name=Available Preview Images
|RECORD=1|LibReference=CAP|PartCount=2|DisplayModeCount=2|IndexInSheet=367|OwnerPartId=-1|Location.X=1390|Location.Y=530|Orientation=2|CurrentPartId=1|SourceLibraryName=Altium Content Vault|TargetFileName=*|AreaColor=11599871|Color=128|PartIDLocked=F|DesignItemId=CMP-2008-00031-1|AllPinCount=2
|RECORD=2|OwnerIndex=2543|OwnerPartId=1|OwnerPartDisplayMode=1|FormalType=1|Electrical=4|PinConglomerate=32|PinLength=10|Location.X=1390|Location.Y=540|Name=1|Designator=1|PinPropagationDelay=0.000000E+000
|RECORD=2|OwnerIndex=2543|OwnerPartId=1|OwnerPartDisplayMode=1|FormalType=1|Electrical=4|PinConglomerate=34|PinLength=10|Location.X=1380|Location.Y=540|Name=2|Designator=2|PinPropagationDelay=0.000000E+000
|RECORD=13|OwnerIndex=2543|IsNotAccesible=T|IndexInSheet=2|OwnerPartId=1|OwnerPartDisplayMode=1|Location.X=1390|Location.Y=548|Corner.X=1390|Corner.Y=532|LineWidth=1|Color=16711680
|RECORD=13|OwnerIndex=2543|IsNotAccesible=T|IndexInSheet=3|OwnerPartId=1|OwnerPartDisplayMode=1|Location.X=1386|Location.Y=540|Corner.X=1380|Corner.Y=540|LineWidth=1|Color=16711680
|RECORD=12|OwnerIndex=2543|IsNotAccesible=T|IndexInSheet=4|OwnerPartId=1|OwnerPartDisplayMode=1|Location.X=1370|Location.Y=540|Radius=16|LineWidth=1|StartAngle=331.000|EndAngle=360.000|Color=16711680
|RECORD=12|OwnerIndex=2543|IsNotAccesible=T|IndexInSheet=5|OwnerPartId=1|OwnerPartDisplayMode=1|Location.X=1370|Location.Y=540|Radius=16|LineWidth=1|StartAngle=360.000|EndAngle=29.000|Color=16711680
|RECORD=2|OwnerIndex=2543|OwnerPartId=1|FormalType=1|Electrical=4|PinConglomerate=32|PinLength=10|Location.X=1390|Location.Y=540|Name=1|Designator=1|PinPropagationDelay=0.000000E+000
|RECORD=2|OwnerIndex=2543|OwnerPartId=1|FormalType=1|Electrical=4|PinConglomerate=34|PinLength=10|Location.X=1380|Location.Y=540|Name=2|Designator=2|PinPropagationDelay=0.000000E+000
|RECORD=13|OwnerIndex=2543|IsNotAccesible=T|IndexInSheet=8|OwnerPartId=1|Location.X=1383|Location.Y=532|Corner.X=1383|Corner.Y=548|LineWidth=1|Color=16711680
|RECORD=13|OwnerIndex=2543|IsNotAccesible=T|IndexInSheet=9|OwnerPartId=1|Location.X=1387|Location.Y=548|Corner.X=1387|Corner.Y=532|LineWidth=1|Color=16711680
|RECORD=6|OwnerIndex=2543|IsNotAccesible=T|IndexInSheet=10|OwnerPartId=1|LineWidth=1|Color=16711680|LocationCount=2|X1=1390|Y1=540|X2=1387|Y2=540
|RECORD=6|OwnerIndex=2543|IsNotAccesible=T|IndexInSheet=11|OwnerPartId=1|LineWidth=1|Color=16711680|LocationCount=2|X1=1380|Y1=540|X2=1383|Y2=540
|RECORD=41|OwnerIndex=2543|IndexInSheet=12|OwnerPartId=-1|Location.X=1368|Location.Y=549|Color=8388608|FontID=1|IsHidden=T|Text=LD02YD104KAB2A|Name=Part Number
|RECORD=41|OwnerIndex=2543|IndexInSheet=13|OwnerPartId=-1|Location.X=1368|Location.Y=549|Color=8388608|FontID=1|IsHidden=T|Text=AVX Interconnect / Elco|Name=Manufacturer
|RECORD=34|OwnerIndex=2543|IndexInSheet=-1|OwnerPartId=-1|Location.X=1379|Location.Y=549|Color=8388608|FontID=1|Text=C33|Name=Designator|ReadOnlyState=1
|RECORD=41|OwnerIndex=2543|IndexInSheet=-1|OwnerPartId=-1|Location.X=1379|Location.Y=521|Color=8388608|FontID=1|Text=0.1uF_0402|Name=Comment
|RECORD=44|OwnerIndex=2543
|RECORD=45|OwnerIndex=2564|IndexInSheet=-1|Description=Chip Capacitor, 2-Leads, Body 1.00x0.50mm, IPC Medium Density|UseComponentLibrary=T|ModelName=CAPC1005X56X25NL10T15|ModelType=PCBLIB|DatafileCount=1|ModelDatafileEntity0=CAPC1005X56X25NL10T15|ModelDatafileKind0=PCBLib|IsCurrent=T|DatalinksLocked=T|DatabaseDatalinksLocked=T
|RECORD=46|OwnerIndex=2565
|RECORD=48|OwnerIndex=2565
|RECORD=41|OwnerIndex=2567|IndexInSheet=-1|OwnerPartId=-1|Color=8388608|FontID=1|IsHidden=T|Text=2D|Name=Available Preview Images
|RECORD=45|OwnerIndex=2564|IndexInSheet=-1|Description=Chip Capacitor, 2-Leads, Body 1.00x0.50mm, IPC High Density|UseComponentLibrary=T|ModelName=CAPC1005X56X25LL10T15|ModelType=PCBLIB|DatafileCount=1|ModelDatafileEntity0=CAPC1005X56X25LL10T15|ModelDatafileKind0=PCBLib|DatalinksLocked=T|DatabaseDatalinksLocked=T
|RECORD=46|OwnerIndex=2569
|RECORD=48|OwnerIndex=2569
|RECORD=41|OwnerIndex=2571|IndexInSheet=-1|OwnerPartId=-1|Color=8388608|FontID=1|IsHidden=T|Text=2D|Name=Available Preview Images
|RECORD=45|OwnerIndex=2564|IndexInSheet=-1|Description=Chip Capacitor, 2-Leads, Body 1.00x0.50mm, IPC Low Density|UseComponentLibrary=T|ModelName=CAPC1005X56X25ML10T15|ModelType=PCBLIB|DatafileCount=1|ModelDatafileEntity0=CAPC1005X56X25ML10T15|ModelDatafileKind0=PCBLib|DatalinksLocked=T|DatabaseDatalinksLocked=T
|RECORD=46|OwnerIndex=2573
|RECORD=48|OwnerIndex=2573
|RECORD=41|OwnerIndex=2575|IndexInSheet=-1|OwnerPartId=-1|Color=8388608|FontID=1|IsHidden=T|Text=2D|Name=Available Preview Images
|RECORD=29|IndexInSheet=-1|OwnerPartId=-1|Location.X=80|Location.Y=590|Color=128
|RECORD=29|IndexInSheet=-1|OwnerPartId=-1|Location.X=80|Location.Y=640|Color=128
|RECORD=29|IndexInSheet=-1|OwnerPartId=-1|Location.X=100|Location.Y=410|Color=128
|RECORD=29|IndexInSheet=-1|OwnerPartId=-1|Location.X=100|Location.Y=460|Color=128
|RECORD=29|IndexInSheet=-1|OwnerPartId=-1|Location.X=120|Location.Y=920|Color=128
|RECORD=29|IndexInSheet=-1|OwnerPartId=-1|Location.X=120|Location.Y=970|Color=128
|RECORD=29|IndexInSheet=-1|OwnerPartId=-1|Location.X=130|Location.Y=640|Color=128
|RECORD=29|IndexInSheet=-1|OwnerPartId=-1|Location.X=150|Location.Y=460|Color=128
|RECORD=29|IndexInSheet=-1|OwnerPartId=-1|Location.X=170|Location.Y=970|Color=128
|RECORD=29|IndexInSheet=-1|OwnerPartId=-1|Location.X=180|Location.Y=590|Color=128
|RECORD=29|IndexInSheet=-1|OwnerPartId=-1|Location.X=180|Location.Y=650|Color=128
|RECORD=29|IndexInSheet=-1|OwnerPartId=-1|Location.X=190|Location.Y=800|Color=128
|RECORD=29|IndexInSheet=-1|OwnerPartId=-1|Location.X=190|Location.Y=850|Color=128
|RECORD=29|IndexInSheet=-1|OwnerPartId=-1|Location.X=200|Location.Y=410|Color=128
|RECORD=29|IndexInSheet=-1|OwnerPartId=-1|Location.X=200|Location.Y=470|Color=128
|RECORD=29|IndexInSheet=-1|OwnerPartId=-1|Location.X=220|Location.Y=920|Color=128
|RECORD=29|IndexInSheet=-1|OwnerPartId=-1|Location.X=220|Location.Y=980|Color=128
|RECORD=29|IndexInSheet=-1|OwnerPartId=-1|Location.X=230|Location.Y=650|Color=128
|RECORD=29|IndexInSheet=-1|OwnerPartId=-1|Location.X=240|Location.Y=850|Color=128
|RECORD=29|IndexInSheet=-1|OwnerPartId=-1|Location.X=250|Location.Y=470|Color=128
|RECORD=29|IndexInSheet=-1|OwnerPartId=-1|Location.X=270|Location.Y=980|Color=128
|RECORD=29|IndexInSheet=-1|OwnerPartId=-1|Location.X=290|Location.Y=800|Color=128
|RECORD=29|IndexInSheet=-1|OwnerPartId=-1|Location.X=290|Location.Y=860|Color=128
|RECORD=29|IndexInSheet=-1|OwnerPartId=-1|Location.X=340|Location.Y=860|Color=128
|RECORD=29|IndexInSheet=-1|OwnerPartId=-1|Location.X=380|Location.Y=620|Color=128
|RECORD=29|IndexInSheet=-1|OwnerPartId=-1|Location.X=390|Location.Y=630|Color=128
|RECORD=29|IndexInSheet=-1|OwnerPartId=-1|Location.X=400|Location.Y=640|Color=128
|RECORD=29|IndexInSheet=-1|OwnerPartId=-1|Location.X=410|Location.Y=650|Color=128
|RECORD=29|IndexInSheet=-1|OwnerPartId=-1|Location.X=470|Location.Y=860|Color=128
|RECORD=29|IndexInSheet=-1|OwnerPartId=-1|Location.X=480|Location.Y=850|Color=128
|RECORD=29|IndexInSheet=-1|OwnerPartId=-1|Location.X=490|Location.Y=840|Color=128
|RECORD=29|IndexInSheet=-1|OwnerPartId=-1|Location.X=500|Location.Y=830|Color=128
|RECORD=29|IndexInSheet=-1|OwnerPartId=-1|Location.X=590|Location.Y=650|Color=128
|RECORD=29|IndexInSheet=-1|OwnerPartId=-1|Location.X=640|Location.Y=640|Color=128
|RECORD=29|IndexInSheet=-1|OwnerPartId=-1|Location.X=650|Location.Y=630|Color=128
|RECORD=29|IndexInSheet=-1|OwnerPartId=-1|Location.X=660|Location.Y=620|Color=128
|RECORD=29|IndexInSheet=-1|OwnerPartId=-1|Location.X=710|Location.Y=860|Color=128
|RECORD=29|IndexInSheet=-1|OwnerPartId=-1|Location.X=750|Location.Y=320|Color=128
|RECORD=29|IndexInSheet=-1|OwnerPartId=-1|Location.X=750|Location.Y=850|Color=128
|RECORD=29|IndexInSheet=-1|OwnerPartId=-1|Location.X=760|Location.Y=840|Color=128
|RECORD=29|IndexInSheet=-1|OwnerPartId=-1|Location.X=770|Location.Y=830|Color=128
|RECORD=29|IndexInSheet=-1|OwnerPartId=-1|Location.X=800|Location.Y=310|Color=128
|RECORD=29|IndexInSheet=-1|OwnerPartId=-1|Location.X=1010|Location.Y=260|Color=128
|RECORD=29|IndexInSheet=-1|OwnerPartId=-1|Location.X=1120|Location.Y=400|Color=128
|RECORD=29|IndexInSheet=-1|OwnerPartId=-1|Location.X=1160|Location.Y=270|Color=128
|RECORD=29|IndexInSheet=-1|OwnerPartId=-1|Location.X=1160|Location.Y=360|Color=128
|RECORD=29|IndexInSheet=-1|OwnerPartId=-1|Location.X=1160|Location.Y=390|Color=128
|RECORD=29|IndexInSheet=-1|OwnerPartId=-1|Location.X=1200|Location.Y=300|Color=128
|RECORD=29|IndexInSheet=-1|OwnerPartId=-1|Location.X=1210|Location.Y=140|Color=128
|RECORD=29|IndexInSheet=-1|OwnerPartId=-1|Location.X=1290|Location.Y=350|Color=128
|RECORD=29|IndexInSheet=-1|OwnerPartId=-1|Location.X=1360|Location.Y=770|Color=128
|RECORD=29|IndexInSheet=-1|OwnerPartId=-1|Location.X=1410|Location.Y=810|Color=128
|RECORD=29|IndexInSheet=-1|OwnerPartId=-1|Location.X=1510|Location.Y=190|Color=128
|RECORD=29|IndexInSheet=-1|OwnerPartId=-1|Location.X=1600|Location.Y=300|Color=128
|RECORD=29|IndexInSheet=-1|OwnerPartId=-1|Location.X=1640|Location.Y=290|Color=128
|RECORD=29|IndexInSheet=-1|OwnerPartId=-1|Location.X=1640|Location.Y=430|Color=128
|RECORD=29|IndexInSheet=-1|OwnerPartId=-1|Location.X=1640|Location.Y=460|Color=128